FILE_TYPE = MACRO_DRAWING;
SET COLOR_WIRE YELLOW;
SET COLOR_PROP MONO;
SET COLOR_DOT WHITE;
SET COLOR_ARC YELLOW;
SET COLOR_BODY GREEN;
SET COLOR_NOTE MONO;
SET PROP_DISPLAY VALUE;
SET PAGE_NUMBER P216;
FORCEADD PVDDQ_ABC..1
(4350 2100);
FORCEPROP 3 LASTPIN (4350 2050) SIG_NAME PVDDQ_ABC\g
J 0
(4360 2060);
DISPLAY 0.659574 (4360 2060);
PAINT MONO (4360 2060);
DISPLAY INVISIBLE (4360 2060);
FORCEPROP 1 LAST HDL_POWER PVDDQ_ABC
J 1
(4350 2150);
DISPLAY 0.872340 (4350 2150);
PAINT GREEN (4350 2150);
DISPLAY INVISIBLE (4350 2150);
FORCEPROP 1 LAST BODY_TYPE PLUMBING
J 0
(4305 2057);
DISPLAY 0.340426 (4305 2057);
PAINT GREEN (4305 2057);
DISPLAY INVISIBLE (4305 2057);
FORCEPROP 1 LAST VOLTAGE 1.2V
J 0
(4305 2057);
DISPLAY 0.340426 (4305 2057);
PAINT SKYBLUE (4305 2057);
DISPLAY INVISIBLE (4305 2057);
FORCEPROP 1 LAST PATH I1
J 0
(4400 2125);
DISPLAY 0.872340 (4400 2125);
PAINT AQUA (4400 2125);
DISPLAY INVISIBLE (4400 2125);
FORCEPROP 2 LAST CDS_LIB mstr_symbols
J 0
(4350 2100);
PAINT ORANGE (4350 2100);
DISPLAY INVISIBLE (4350 2100);
FORCEADD IR354XX..1
(1775 2300);
FORCEPROP 2 LASTPIN (1275 1950) $PN 32
J 2
(1265 1960);
DISPLAY 0.617021 (1265 1960);
PAINT ORANGE (1265 1960);
FORCEPROP 2 LASTPIN (1275 2000) $PN 33
J 2
(1265 2010);
DISPLAY 0.617021 (1265 2010);
PAINT ORANGE (1265 2010);
FORCEPROP 1 LAST PART_NUMBER H73688-001
J 0
(1425 1600);
DISPLAY 0.617021 (1425 1600);
PAINT BLUE (1425 1600);
FORCEPROP 2 LASTPIN (1275 2200) $PN 34
J 2
(1265 2210);
DISPLAY 0.617021 (1265 2210);
PAINT ORANGE (1265 2210);
FORCEPROP 2 LASTPIN (1275 2100) $PN 39
J 2
(1265 2110);
DISPLAY 0.617021 (1265 2110);
PAINT ORANGE (1265 2110);
FORCEPROP 2 LASTPIN (1275 2350) $PN 41
J 2
(1265 2360);
DISPLAY 0.617021 (1265 2360);
PAINT ORANGE (1265 2360);
FORCEPROP 2 LASTPIN (1275 2300) $PN 6
J 2
(1265 2310);
DISPLAY 0.617021 (1265 2310);
PAINT ORANGE (1265 2310);
FORCEPROP 2 LASTPIN (1275 2450) $PN 1
J 2
(1265 2460);
DISPLAY 0.617021 (1265 2460);
PAINT ORANGE (1265 2460);
FORCEPROP 2 LASTPIN (1275 2550) $PN 35
J 2
(1265 2560);
DISPLAY 0.617021 (1265 2560);
PAINT ORANGE (1265 2560);
FORCEPROP 2 LASTPIN (1275 2750) $PN 25
J 2
(1265 2760);
DISPLAY 0.617021 (1265 2760);
PAINT ORANGE (1265 2760);
FORCEPROP 2 LASTPIN (1275 2650) $PN 4
J 2
(1265 2660);
DISPLAY 0.617021 (1265 2660);
PAINT ORANGE (1265 2660);
FORCEPROP 2 LASTPIN (1275 2800) $PN 30
J 2
(1265 2810);
DISPLAY 0.617021 (1265 2810);
PAINT ORANGE (1265 2810);
FORCEPROP 2 LASTPIN (1275 2850) $PN 3
J 2
(1265 2860);
DISPLAY 0.617021 (1265 2860);
PAINT ORANGE (1265 2860);
FORCEPROP 1 LAST MATERIAL IC
J 0
(1325 3050);
DISPLAY 0.617021 (1325 3050);
PAINT SKYBLUE (1325 3050);
FORCEPROP 1 LAST LOCATION EU7G2
J 0
(1325 3100);
DISPLAY 0.617021 (1325 3100);
PAINT AQUA (1325 3100);
FORCEPROP 2 LAST NO_XNET_CONNECTION 1
J 0
(1325 3150);
PAINT MONO (1325 3150);
FORCEPROP 2 LASTPIN (2275 1850) $PN 40
J 0
(2285 1860);
DISPLAY 0.617021 (2285 1860);
PAINT ORANGE (2285 1860);
FORCEPROP 2 LASTPIN (2275 1900) $PN 2
J 0
(2285 1910);
DISPLAY 0.617021 (2285 1910);
PAINT ORANGE (2285 1910);
FORCEPROP 2 LASTPIN (2275 2000) $PN 10
J 0
(2285 2010);
DISPLAY 0.617021 (2285 2010);
PAINT ORANGE (2285 2010);
FORCEPROP 2 LASTPIN (2275 1750) $PN 5
J 0
(2285 1760);
DISPLAY 0.617021 (2285 1760);
PAINT ORANGE (2285 1760);
FORCEPROP 2 LASTPIN (2275 1800) $PN 7
J 0
(2285 1810);
DISPLAY 0.617021 (2285 1810);
PAINT ORANGE (2285 1810);
FORCEPROP 2 LASTPIN (2275 2350) $PN 36
J 0
(2285 2360);
DISPLAY 0.617021 (2285 2360);
PAINT ORANGE (2285 2360);
FORCEPROP 2 LASTPIN (2275 2600) $PN 31
J 0
(2285 2610);
DISPLAY 0.617021 (2285 2610);
PAINT ORANGE (2285 2610);
FORCEPROP 2 LASTPIN (2275 2650) $PN 37
J 0
(2285 2660);
DISPLAY 0.617021 (2285 2660);
PAINT ORANGE (2285 2660);
FORCEPROP 2 LASTPIN (2275 2850) $PN 38
J 0
(2285 2860);
DISPLAY 0.617021 (2285 2860);
PAINT ORANGE (2285 2860);
FORCEPROP 1 LAST VALUE IR35411
J 1
(1775 2925);
DISPLAY 0.617021 (1775 2925);
PAINT SKYBLUE (1775 2925);
DISPLAY INVISIBLE (1775 2925);
FORCEPROP 2 LAST CDS_LOCATION EU7G2
J 0
(1325 3100);
DISPLAY 0.617021 (1325 3100);
PAINT AQUA (1325 3100);
DISPLAY INVISIBLE (1325 3100);
FORCEPROP 2 LAST SEC 1
J 0
(1325 3150);
DISPLAY 0.680851 (1325 3150);
PAINT MONO (1325 3150);
DISPLAY INVISIBLE (1325 3150);
FORCEPROP 2 LAST SEC_TYPE SM
J 0
(1325 3150);
DISPLAY 1.021277 (1325 3150);
PAINT ORANGE (1325 3150);
DISPLAY INVISIBLE (1325 3150);
FORCEPROP 1 LAST PACK_TYPE SM
J 0
(1325 3150);
PAINT SKYBLUE (1325 3150);
DISPLAY INVISIBLE (1325 3150);
FORCEPROP 1 LAST PATH I102
J 0
(1775 3050);
PAINT GREEN (1775 3050);
DISPLAY INVISIBLE (1775 3050);
FORCEPROP 2 LAST CDS_LIB mstr_discrete
J 0
(1775 2300);
PAINT ORANGE (1775 2300);
DISPLAY INVISIBLE (1775 2300);
FORCEADD IR354XX..1
(1775 -75);
FORCEPROP 2 LASTPIN (1275 -425) $PN 32
J 2
(1265 -415);
DISPLAY 0.617021 (1265 -415);
PAINT ORANGE (1265 -415);
FORCEPROP 2 LASTPIN (1275 -375) $PN 33
J 2
(1265 -365);
DISPLAY 0.617021 (1265 -365);
PAINT ORANGE (1265 -365);
FORCEPROP 2 LASTPIN (1275 -275) $PN 39
J 2
(1265 -265);
DISPLAY 0.617021 (1265 -265);
PAINT ORANGE (1265 -265);
FORCEPROP 2 LASTPIN (1275 -75) $PN 6
J 2
(1265 -65);
DISPLAY 0.617021 (1265 -65);
PAINT ORANGE (1265 -65);
FORCEPROP 2 LASTPIN (1275 -175) $PN 34
J 2
(1265 -165);
DISPLAY 0.617021 (1265 -165);
PAINT ORANGE (1265 -165);
FORCEPROP 1 LAST PART_NUMBER H73688-001
J 0
(1325 -775);
DISPLAY 0.617021 (1325 -775);
PAINT BLUE (1325 -775);
FORCEPROP 0 LAST BOM_SS NOPOP
J 0
(1325 -825);
DISPLAY 0.638298 (1325 -825);
PAINT BROWN (1325 -825);
DISPLAY BOTH (1325 -825);
FORCEPROP 2 LASTPIN (2275 -575) $PN 7
J 0
(2285 -565);
DISPLAY 0.617021 (2285 -565);
PAINT ORANGE (2285 -565);
FORCEPROP 2 LASTPIN (2275 -625) $PN 5
J 0
(2285 -615);
DISPLAY 0.617021 (2285 -615);
PAINT ORANGE (2285 -615);
FORCEPROP 2 LASTPIN (2275 -525) $PN 40
J 0
(2285 -515);
DISPLAY 0.617021 (2285 -515);
PAINT ORANGE (2285 -515);
FORCEPROP 2 LASTPIN (2275 -375) $PN 10
J 0
(2285 -365);
DISPLAY 0.617021 (2285 -365);
PAINT ORANGE (2285 -365);
FORCEPROP 2 LASTPIN (2275 -475) $PN 2
J 0
(2285 -465);
DISPLAY 0.617021 (2285 -465);
PAINT ORANGE (2285 -465);
FORCEPROP 2 LASTPIN (2275 -25) $PN 36
J 0
(2285 -15);
DISPLAY 0.617021 (2285 -15);
PAINT ORANGE (2285 -15);
FORCEPROP 2 LASTPIN (1275 -25) $PN 41
J 2
(1265 -15);
DISPLAY 0.617021 (1265 -15);
PAINT ORANGE (1265 -15);
FORCEPROP 2 LASTPIN (1275 75) $PN 1
J 2
(1265 85);
DISPLAY 0.617021 (1265 85);
PAINT ORANGE (1265 85);
FORCEPROP 2 LASTPIN (1275 175) $PN 35
J 2
(1265 185);
DISPLAY 0.617021 (1265 185);
PAINT ORANGE (1265 185);
FORCEPROP 2 LASTPIN (1275 275) $PN 4
J 2
(1265 285);
DISPLAY 0.617021 (1265 285);
PAINT ORANGE (1265 285);
FORCEPROP 2 LASTPIN (1275 375) $PN 25
J 2
(1265 385);
DISPLAY 0.617021 (1265 385);
PAINT ORANGE (1265 385);
FORCEPROP 2 LASTPIN (1275 475) $PN 3
J 2
(1265 485);
DISPLAY 0.617021 (1265 485);
PAINT ORANGE (1265 485);
FORCEPROP 2 LASTPIN (1275 425) $PN 30
J 2
(1265 435);
DISPLAY 0.617021 (1265 435);
PAINT ORANGE (1265 435);
FORCEPROP 1 LAST LOCATION EU7G3
J 0
(1325 725);
DISPLAY 0.617021 (1325 725);
PAINT AQUA (1325 725);
FORCEPROP 1 LAST MATERIAL IC
J 0
(1325 675);
DISPLAY 0.617021 (1325 675);
PAINT SKYBLUE (1325 675);
FORCEPROP 2 LAST NO_XNET_CONNECTION 1
J 0
(1325 775);
PAINT MONO (1325 775);
FORCEPROP 2 LASTPIN (2275 475) $PN 38
J 0
(2285 485);
DISPLAY 0.617021 (2285 485);
PAINT ORANGE (2285 485);
FORCEPROP 2 LASTPIN (2275 225) $PN 31
J 0
(2285 235);
DISPLAY 0.617021 (2285 235);
PAINT ORANGE (2285 235);
FORCEPROP 2 LASTPIN (2275 275) $PN 37
J 0
(2285 285);
DISPLAY 0.617021 (2285 285);
PAINT ORANGE (2285 285);
FORCEPROP 1 LAST VALUE IR35411
J 1
(1775 550);
DISPLAY 0.617021 (1775 550);
PAINT SKYBLUE (1775 550);
DISPLAY INVISIBLE (1775 550);
FORCEPROP 2 LAST CDS_LIB mstr_discrete
J 0
(1775 -75);
PAINT ORANGE (1775 -75);
DISPLAY INVISIBLE (1775 -75);
FORCEPROP 2 LAST CDS_LOCATION EU7G3
J 0
(1325 725);
DISPLAY 0.617021 (1325 725);
PAINT AQUA (1325 725);
DISPLAY INVISIBLE (1325 725);
FORCEPROP 2 LAST SEC 1
J 0
(1325 775);
DISPLAY 0.680851 (1325 775);
PAINT MONO (1325 775);
DISPLAY INVISIBLE (1325 775);
FORCEPROP 2 LAST SEC_TYPE SM
J 0
(1325 775);
DISPLAY 1.021277 (1325 775);
PAINT ORANGE (1325 775);
DISPLAY INVISIBLE (1325 775);
FORCEPROP 1 LAST PACK_TYPE SM
J 0
(1325 775);
PAINT SKYBLUE (1325 775);
DISPLAY INVISIBLE (1325 775);
FORCEPROP 1 LAST PATH I103
J 0
(1775 675);
PAINT GREEN (1775 675);
DISPLAY INVISIBLE (1775 675);
FORCEADD RES..2
(4575 2450);
FORCEPROP 1 LASTPIN (4575 2550) $PN 1
J 0
(4580 2512);
DISPLAY 0.617021 (4580 2512);
PAINT ORANGE (4580 2512);
FORCEPROP 1 LASTPIN (4575 2350) $PN 2
J 0
(4580 2360);
DISPLAY 0.617021 (4580 2360);
PAINT ORANGE (4580 2360);
FORCEPROP 1 LAST PACK_TYPE 0402
J 0
(4615 2275);
DISPLAY 0.617021 (4615 2275);
PAINT SKYBLUE (4615 2275);
FORCEPROP 1 LAST TOLERANCE 1%
J 0
(4620 2475);
DISPLAY 0.617021 (4620 2475);
PAINT SKYBLUE (4620 2475);
FORCEPROP 1 LAST VALUE 68.1K
J 0
(4620 2525);
DISPLAY 0.617021 (4620 2525);
PAINT SKYBLUE (4620 2525);
FORCEPROP 1 LAST MATERIAL EMPTY
J 0
(4615 2375);
DISPLAY 0.617021 (4615 2375);
PAINT RED (4615 2375);
FORCEPROP 1 LAST WATTAGE 1/16W
J 0
(4615 2425);
DISPLAY 0.617021 (4615 2425);
PAINT SKYBLUE (4615 2425);
FORCEPROP 1 LAST PART_NUMBER G21796-187
J 0
(4615 2325);
DISPLAY 0.617021 (4615 2325);
PAINT BLUE (4615 2325);
FORCEPROP 1 LAST LOCATION R7G25
J 0
(4620 2575);
DISPLAY 0.617021 (4620 2575);
PAINT AQUA (4620 2575);
FORCEPROP 2 LAST CDS_LIB mstr_discrete
J 0
(4575 2450);
PAINT ORANGE (4575 2450);
DISPLAY INVISIBLE (4575 2450);
FORCEPROP 1 LAST PATH I104
J 0
(4625 2625);
DISPLAY 0.978723 (4625 2625);
PAINT WHITE (4625 2625);
DISPLAY INVISIBLE (4625 2625);
FORCEPROP 0 LAST SEC 1
J 0
(4625 2625);
DISPLAY 0.680851 (4625 2625);
PAINT MONO (4625 2625);
DISPLAY INVISIBLE (4625 2625);
FORCEPROP 2 LAST SEC_TYPE 0402
J 0
(4625 2675);
DISPLAY 1.021277 (4625 2675);
PAINT ORANGE (4625 2675);
DISPLAY INVISIBLE (4625 2675);
FORCEADD GND..1
(4575 2250);
FORCEPROP 3 LASTPIN (4575 2300) SIG_NAME GND\g
J 0
(4585 2310);
DISPLAY 0.659574 (4585 2310);
PAINT MONO (4585 2310);
DISPLAY INVISIBLE (4585 2310);
FORCEPROP 1 LAST HDL_POWER GND
J 0
(4575 2400);
DISPLAY 1.723404 (4575 2400);
PAINT GREEN (4575 2400);
DISPLAY INVISIBLE (4575 2400);
FORCEPROP 1 LAST BODY_TYPE PLUMBING
J 0
(4530 2207);
DISPLAY 0.340426 (4530 2207);
PAINT GREEN (4530 2207);
DISPLAY INVISIBLE (4530 2207);
FORCEPROP 1 LAST PATH I105
J 0
(4650 2250);
DISPLAY 0.872340 (4650 2250);
PAINT AQUA (4650 2250);
DISPLAY INVISIBLE (4650 2250);
FORCEPROP 1 LAST SIZE 1B
J 0
(4650 2200);
DISPLAY 1.723404 (4650 2200);
PAINT GREEN (4650 2200);
DISPLAY INVISIBLE (4650 2200);
FORCEPROP 2 LAST CDS_LIB mstr_symbols
J 0
(4575 2250);
PAINT ORANGE (4575 2250);
DISPLAY INVISIBLE (4575 2250);
FORCEPROP 1 LAST VOLTAGE 0
J 0
(4575 2250);
PAINT SKYBLUE (4575 2250);
DISPLAY INVISIBLE (4575 2250);
FORCEPROP 2 LAST BOM_COST PROC_VRD_VCCIN_CPU0
J 0
(4200 2325);
DISPLAY 1.446809 (4200 2325);
PAINT MONO (4200 2325);
DISPLAY INVISIBLE (4200 2325);
FORCEPROP 2 LAST ROOM PVCCIN_CPU0_PWR_VR
J 0
(4025 2325);
DISPLAY 1.936170 (4025 2325);
PAINT ORANGE (4025 2325);
DISPLAY INVISIBLE (4025 2325);
FORCEADD RES..2
(4675 50);
FORCEPROP 1 LASTPIN (4675 -50) $PN 2
J 0
(4680 -40);
DISPLAY 0.617021 (4680 -40);
PAINT ORANGE (4680 -40);
FORCEPROP 1 LAST PACK_TYPE 0402
J 0
(4715 -125);
DISPLAY 0.617021 (4715 -125);
PAINT SKYBLUE (4715 -125);
FORCEPROP 1 LAST PART_NUMBER G21796-187
J 0
(4715 -75);
DISPLAY 0.617021 (4715 -75);
PAINT BLUE (4715 -75);
FORCEPROP 0 LAST BOM_SS NOPOP
J 0
(4700 -175);
DISPLAY 0.638298 (4700 -175);
PAINT BROWN (4700 -175);
DISPLAY BOTH (4700 -175);
FORCEPROP 1 LAST MATERIAL EMPTY
J 0
(4715 -25);
DISPLAY 0.617021 (4715 -25);
PAINT RED (4715 -25);
FORCEPROP 1 LASTPIN (4675 150) $PN 1
J 0
(4680 112);
DISPLAY 0.617021 (4680 112);
PAINT ORANGE (4680 112);
FORCEPROP 1 LAST WATTAGE 1/16W
J 0
(4715 25);
DISPLAY 0.617021 (4715 25);
PAINT SKYBLUE (4715 25);
FORCEPROP 1 LAST TOLERANCE 1%
J 0
(4720 75);
DISPLAY 0.617021 (4720 75);
PAINT SKYBLUE (4720 75);
FORCEPROP 1 LAST VALUE 68.1K
J 0
(4720 125);
DISPLAY 0.617021 (4720 125);
PAINT SKYBLUE (4720 125);
FORCEPROP 1 LAST LOCATION R7G30
J 0
(4720 175);
DISPLAY 0.617021 (4720 175);
PAINT AQUA (4720 175);
FORCEPROP 2 LAST CDS_LIB mstr_discrete
J 0
(4675 50);
PAINT ORANGE (4675 50);
DISPLAY INVISIBLE (4675 50);
FORCEPROP 1 LAST PATH I106
J 0
(4725 225);
DISPLAY 0.978723 (4725 225);
PAINT WHITE (4725 225);
DISPLAY INVISIBLE (4725 225);
FORCEPROP 0 LAST SEC 1
J 0
(4725 225);
DISPLAY 0.680851 (4725 225);
PAINT MONO (4725 225);
DISPLAY INVISIBLE (4725 225);
FORCEPROP 2 LAST SEC_TYPE 0402
J 0
(4725 275);
DISPLAY 1.021277 (4725 275);
PAINT ORANGE (4725 275);
DISPLAY INVISIBLE (4725 275);
FORCEADD GND..1
(4675 -175);
FORCEPROP 3 LASTPIN (4675 -125) SIG_NAME GND\g
J 0
(4685 -115);
DISPLAY 0.659574 (4685 -115);
PAINT MONO (4685 -115);
DISPLAY INVISIBLE (4685 -115);
FORCEPROP 1 LAST HDL_POWER GND
J 0
(4675 -25);
DISPLAY 1.723404 (4675 -25);
PAINT GREEN (4675 -25);
DISPLAY INVISIBLE (4675 -25);
FORCEPROP 1 LAST BODY_TYPE PLUMBING
J 0
(4630 -218);
DISPLAY 0.340426 (4630 -218);
PAINT GREEN (4630 -218);
DISPLAY INVISIBLE (4630 -218);
FORCEPROP 2 LAST ROOM PVCCIN_CPU0_PWR_VR
J 0
(4125 -100);
DISPLAY 1.936170 (4125 -100);
PAINT ORANGE (4125 -100);
DISPLAY INVISIBLE (4125 -100);
FORCEPROP 2 LAST BOM_COST PROC_VRD_VCCIN_CPU0
J 0
(4300 -100);
DISPLAY 1.446809 (4300 -100);
PAINT MONO (4300 -100);
DISPLAY INVISIBLE (4300 -100);
FORCEPROP 2 LAST CDS_LIB mstr_symbols
J 0
(4675 -175);
PAINT ORANGE (4675 -175);
DISPLAY INVISIBLE (4675 -175);
FORCEPROP 1 LAST VOLTAGE 0
J 0
(4675 -175);
PAINT SKYBLUE (4675 -175);
DISPLAY INVISIBLE (4675 -175);
FORCEPROP 1 LAST SIZE 1B
J 0
(4750 -225);
DISPLAY 1.723404 (4750 -225);
PAINT GREEN (4750 -225);
DISPLAY INVISIBLE (4750 -225);
FORCEPROP 1 LAST PATH I107
J 0
(4750 -175);
DISPLAY 0.872340 (4750 -175);
PAINT AQUA (4750 -175);
DISPLAY INVISIBLE (4750 -175);
FORCEADD CAP_A..1
(1025 1800);
FORCEPROP 1 LASTPIN (1025 1700) $PN 2
J 0
(1035 1680);
DISPLAY 0.787234 (1035 1680);
PAINT ORANGE (1035 1680);
FORCEPROP 1 LAST TOLERANCE 10%
J 0
(1075 1750);
DISPLAY 0.617021 (1075 1750);
PAINT SKYBLUE (1075 1750);
FORCEPROP 1 LAST PACK_TYPE 0402V
J 0
(1075 1600);
DISPLAY 0.617021 (1075 1600);
PAINT SKYBLUE (1075 1600);
FORCEPROP 1 LAST MATERIAL X7R
J 0
(1075 1700);
DISPLAY 0.617021 (1075 1700);
PAINT SKYBLUE (1075 1700);
FORCEPROP 1 LASTPIN (1025 1900) $PN 1
J 0
(1035 1880);
DISPLAY 0.787234 (1035 1880);
PAINT ORANGE (1035 1880);
FORCEPROP 1 LAST VALUE 0.1UF
J 0
(1075 1850);
DISPLAY 0.617021 (1075 1850);
PAINT SKYBLUE (1075 1850);
FORCEPROP 1 LAST VOLTAGE 16V
J 0
(1075 1800);
DISPLAY 0.617021 (1075 1800);
PAINT SKYBLUE (1075 1800);
FORCEPROP 1 LAST LOCATION CT51
J 0
(1075 1900);
DISPLAY 0.617021 (1075 1900);
PAINT AQUA (1075 1900);
FORCEPROP 1 LAST PART_NUMBER A36096-030
J 0
(1075 1650);
DISPLAY 0.617021 (1075 1650);
PAINT BLUE (1075 1650);
FORCEPROP 0 LAST POP NOPOP
J 0
(1063 1542);
DISPLAY 1.021277 (1063 1542);
PAINT RED (1063 1542);
FORCEPROP 2 LAST SEC_TYPE 0402V
J 0
(1075 2000);
DISPLAY 1.021277 (1075 2000);
PAINT ORANGE (1075 2000);
DISPLAY INVISIBLE (1075 2000);
FORCEPROP 0 LAST SEC 1
J 0
(1050 1925);
DISPLAY 0.680851 (1050 1925);
PAINT MONO (1050 1925);
DISPLAY INVISIBLE (1050 1925);
FORCEPROP 2 LAST CDS_LIB dev_discrete
J 0
(1025 1800);
PAINT MONO (1025 1800);
DISPLAY INVISIBLE (1025 1800);
FORCEPROP 1 LAST PATH I108
J 0
(1075 1950);
DISPLAY 0.978723 (1075 1950);
PAINT WHITE (1075 1950);
DISPLAY INVISIBLE (1075 1950);
FORCEPROP 2 LAST ROOM PVCCIN_CPU0_PWR_VR
J 0
(1075 1950);
DISPLAY 1.361702 (1075 1950);
PAINT ORANGE (1075 1950);
DISPLAY INVISIBLE (1075 1950);
FORCEADD GND..1
(1025 1550);
FORCEPROP 3 LASTPIN (1025 1600) SIG_NAME GND\g
J 0
(1035 1610);
DISPLAY 0.659574 (1035 1610);
PAINT MONO (1035 1610);
DISPLAY INVISIBLE (1035 1610);
FORCEPROP 1 LAST HDL_POWER GND
J 0
(1025 1700);
DISPLAY 1.723404 (1025 1700);
PAINT GREEN (1025 1700);
DISPLAY INVISIBLE (1025 1700);
FORCEPROP 1 LAST BODY_TYPE PLUMBING
J 0
(980 1507);
DISPLAY 0.340426 (980 1507);
PAINT GREEN (980 1507);
DISPLAY INVISIBLE (980 1507);
FORCEPROP 2 LAST CDS_LIB mstr_symbols
J 0
(1025 1550);
PAINT MONO (1025 1550);
DISPLAY INVISIBLE (1025 1550);
FORCEPROP 1 LAST PATH I109
J 0
(1100 1550);
DISPLAY 0.872340 (1100 1550);
PAINT AQUA (1100 1550);
DISPLAY INVISIBLE (1100 1550);
FORCEPROP 1 LAST VOLTAGE 0
J 0
(1025 1550);
PAINT SKYBLUE (1025 1550);
DISPLAY INVISIBLE (1025 1550);
FORCEPROP 1 LAST SIZE 1B
J 0
(1100 1500);
DISPLAY 1.723404 (1100 1500);
PAINT GREEN (1100 1500);
DISPLAY INVISIBLE (1100 1500);
FORCEPROP 2 LAST BOM_COST PROC_VRD_VCCIN_CPU0
J 0
(650 1625);
DISPLAY 1.446809 (650 1625);
PAINT MONO (650 1625);
DISPLAY INVISIBLE (650 1625);
FORCEPROP 2 LAST ROOM PVCCIN_CPU0_PWR_VR
J 0
(475 1625);
DISPLAY 1.936170 (475 1625);
PAINT ORANGE (475 1625);
DISPLAY INVISIBLE (475 1625);
FORCEADD CAP_A..1
(1125 -950);
FORCEPROP 1 LAST LOCATION CT52
J 0
(1000 -925);
DISPLAY 0.617021 (1000 -925);
PAINT AQUA (1000 -925);
FORCEPROP 1 LASTPIN (1125 -1050) $PN 2
J 0
(1135 -1070);
DISPLAY 0.787234 (1135 -1070);
PAINT ORANGE (1135 -1070);
FORCEPROP 1 LAST MATERIAL X7R
J 0
(1175 -1050);
DISPLAY 0.617021 (1175 -1050);
PAINT SKYBLUE (1175 -1050);
FORCEPROP 1 LAST PACK_TYPE 0402V
J 0
(1175 -1150);
DISPLAY 0.617021 (1175 -1150);
PAINT SKYBLUE (1175 -1150);
FORCEPROP 1 LAST PART_NUMBER A36096-030
J 0
(1175 -1100);
DISPLAY 0.617021 (1175 -1100);
PAINT BLUE (1175 -1100);
FORCEPROP 0 LAST POP NOPOP
J 0
(1186 -1202);
DISPLAY 1.021277 (1186 -1202);
PAINT RED (1186 -1202);
FORCEPROP 0 LAST BOM_SS NOPOP
J 0
(1450 -1175);
DISPLAY 0.638298 (1450 -1175);
PAINT BROWN (1450 -1175);
DISPLAY BOTH (1450 -1175);
FORCEPROP 1 LASTPIN (1125 -850) $PN 1
J 0
(1135 -870);
DISPLAY 0.787234 (1135 -870);
PAINT ORANGE (1135 -870);
FORCEPROP 1 LAST VOLTAGE 16V
J 0
(1175 -950);
DISPLAY 0.617021 (1175 -950);
PAINT SKYBLUE (1175 -950);
FORCEPROP 1 LAST TOLERANCE 10%
J 0
(1175 -1000);
DISPLAY 0.617021 (1175 -1000);
PAINT SKYBLUE (1175 -1000);
FORCEPROP 1 LAST VALUE 0.1UF
J 0
(1175 -900);
DISPLAY 0.617021 (1175 -900);
PAINT SKYBLUE (1175 -900);
FORCEPROP 0 LAST SEC 1
J 0
(1175 -850);
DISPLAY 0.680851 (1175 -850);
PAINT MONO (1175 -850);
DISPLAY INVISIBLE (1175 -850);
FORCEPROP 2 LAST SEC_TYPE 0402V
J 0
(1175 -750);
DISPLAY 1.021277 (1175 -750);
PAINT ORANGE (1175 -750);
DISPLAY INVISIBLE (1175 -750);
FORCEPROP 2 LAST ROOM PVCCIN_CPU0_PWR_VR
J 0
(1175 -800);
DISPLAY 1.361702 (1175 -800);
PAINT ORANGE (1175 -800);
DISPLAY INVISIBLE (1175 -800);
FORCEPROP 1 LAST PATH I111
J 0
(1175 -800);
DISPLAY 0.978723 (1175 -800);
PAINT WHITE (1175 -800);
DISPLAY INVISIBLE (1175 -800);
FORCEPROP 2 LAST CDS_LIB dev_discrete
J 0
(1125 -950);
PAINT MONO (1125 -950);
DISPLAY INVISIBLE (1125 -950);
FORCEADD GND..1
(1125 -1150);
FORCEPROP 3 LASTPIN (1125 -1100) SIG_NAME GND\g
J 0
(1135 -1090);
DISPLAY 0.659574 (1135 -1090);
PAINT MONO (1135 -1090);
DISPLAY INVISIBLE (1135 -1090);
FORCEPROP 1 LAST HDL_POWER GND
J 0
(1125 -1000);
DISPLAY 1.723404 (1125 -1000);
PAINT GREEN (1125 -1000);
DISPLAY INVISIBLE (1125 -1000);
FORCEPROP 1 LAST BODY_TYPE PLUMBING
J 0
(1080 -1193);
DISPLAY 0.340426 (1080 -1193);
PAINT GREEN (1080 -1193);
DISPLAY INVISIBLE (1080 -1193);
FORCEPROP 2 LAST ROOM PVCCIN_CPU0_PWR_VR
J 0
(575 -1075);
DISPLAY 1.936170 (575 -1075);
PAINT ORANGE (575 -1075);
DISPLAY INVISIBLE (575 -1075);
FORCEPROP 2 LAST BOM_COST PROC_VRD_VCCIN_CPU0
J 0
(750 -1075);
DISPLAY 1.446809 (750 -1075);
PAINT MONO (750 -1075);
DISPLAY INVISIBLE (750 -1075);
FORCEPROP 1 LAST SIZE 1B
J 0
(1200 -1200);
DISPLAY 1.723404 (1200 -1200);
PAINT GREEN (1200 -1200);
DISPLAY INVISIBLE (1200 -1200);
FORCEPROP 1 LAST VOLTAGE 0
J 0
(1125 -1150);
PAINT SKYBLUE (1125 -1150);
DISPLAY INVISIBLE (1125 -1150);
FORCEPROP 1 LAST PATH I112
J 0
(1200 -1150);
DISPLAY 0.872340 (1200 -1150);
PAINT AQUA (1200 -1150);
DISPLAY INVISIBLE (1200 -1150);
FORCEPROP 2 LAST CDS_LIB mstr_symbols
J 0
(1125 -1150);
PAINT MONO (1125 -1150);
DISPLAY INVISIBLE (1125 -1150);
FORCEADD GND..1
(2900 1275);
FORCEPROP 3 LASTPIN (2900 1325) SIG_NAME GND\g
J 0
(2910 1335);
DISPLAY 0.659574 (2910 1335);
PAINT MONO (2910 1335);
DISPLAY INVISIBLE (2910 1335);
FORCEPROP 2 LAST ROOM PVCCIN_CPU0_PWR_VR
J 0
(2350 1350);
DISPLAY 1.936170 (2350 1350);
PAINT ORANGE (2350 1350);
DISPLAY INVISIBLE (2350 1350);
FORCEPROP 2 LAST BOM_COST PROC_VRD_VCCIN_CPU0
J 0
(2525 1350);
DISPLAY 1.446809 (2525 1350);
PAINT MONO (2525 1350);
DISPLAY INVISIBLE (2525 1350);
FORCEPROP 1 LAST VOLTAGE 0
J 0
(2900 1275);
PAINT SKYBLUE (2900 1275);
DISPLAY INVISIBLE (2900 1275);
FORCEPROP 1 LAST SIZE 1B
J 0
(2975 1225);
DISPLAY 1.723404 (2975 1225);
PAINT GREEN (2975 1225);
DISPLAY INVISIBLE (2975 1225);
FORCEPROP 1 LAST PATH I115
J 0
(2975 1275);
DISPLAY 0.872340 (2975 1275);
PAINT AQUA (2975 1275);
DISPLAY INVISIBLE (2975 1275);
FORCEPROP 2 LAST CDS_LIB mstr_symbols
J 0
(2900 1275);
PAINT MONO (2900 1275);
DISPLAY INVISIBLE (2900 1275);
FORCEPROP 1 LAST BODY_TYPE PLUMBING
J 0
(2855 1232);
DISPLAY 0.340426 (2855 1232);
PAINT GREEN (2855 1232);
DISPLAY INVISIBLE (2855 1232);
FORCEPROP 1 LAST HDL_POWER GND
J 0
(2900 1425);
DISPLAY 1.723404 (2900 1425);
PAINT GREEN (2900 1425);
DISPLAY INVISIBLE (2900 1425);
FORCEADD GND..1
(3000 2175);
FORCEPROP 3 LASTPIN (3000 2225) SIG_NAME GND\g
J 0
(3010 2235);
DISPLAY 0.659574 (3010 2235);
PAINT MONO (3010 2235);
DISPLAY INVISIBLE (3010 2235);
FORCEPROP 1 LAST HDL_POWER GND
J 0
(3000 2325);
DISPLAY 1.170213 (3000 2325);
PAINT GREEN (3000 2325);
DISPLAY INVISIBLE (3000 2325);
FORCEPROP 1 LAST BODY_TYPE PLUMBING
J 0
(2955 2132);
DISPLAY 0.340426 (2955 2132);
PAINT GREEN (2955 2132);
DISPLAY INVISIBLE (2955 2132);
FORCEPROP 2 LAST ROOM VDDQ_KLM_PWR_VR
J 0
(2425 2250);
DISPLAY 1.361702 (2425 2250);
PAINT ORANGE (2425 2250);
DISPLAY INVISIBLE (2425 2250);
FORCEPROP 1 LAST VOLTAGE 0
J 0
(3000 2175);
PAINT SKYBLUE (3000 2175);
DISPLAY INVISIBLE (3000 2175);
FORCEPROP 1 LAST SIZE 1B
J 0
(3075 2125);
DISPLAY 1.170213 (3075 2125);
PAINT AQUA (3075 2125);
DISPLAY INVISIBLE (3075 2125);
FORCEPROP 1 LAST PATH I117
J 0
(3075 2175);
DISPLAY 0.872340 (3075 2175);
PAINT AQUA (3075 2175);
DISPLAY INVISIBLE (3075 2175);
FORCEPROP 2 LAST CDS_LIB mstr_symbols
J 0
(3000 2175);
PAINT MONO (3000 2175);
DISPLAY INVISIBLE (3000 2175);
FORCEADD CAP..1
(3000 2375);
FORCEPROP 0 LAST POP NOPOP
J 0
(2775 2275);
DISPLAY 1.021277 (2775 2275);
PAINT RED (2775 2275);
FORCEPROP 1 LASTPIN (3000 2275) $PN 2
J 0
(3010 2255);
DISPLAY 0.787234 (3010 2255);
PAINT ORANGE (3010 2255);
FORCEPROP 1 LAST LOCATION CT49
J 0
(2850 2375);
DISPLAY 0.617021 (2850 2375);
PAINT AQUA (2850 2375);
FORCEPROP 1 LASTPIN (3000 2475) $PN 1
J 0
(3010 2455);
DISPLAY 0.787234 (3010 2455);
PAINT ORANGE (3010 2455);
FORCEPROP 1 LAST PART_NUMBER A36096-046
J 0
(3050 2225);
DISPLAY 0.617021 (3050 2225);
PAINT BLUE (3050 2225);
FORCEPROP 1 LAST MATERIAL X7R
J 0
(3050 2275);
DISPLAY 0.617021 (3050 2275);
PAINT SKYBLUE (3050 2275);
FORCEPROP 1 LAST TOLERANCE 10%
J 0
(3050 2325);
DISPLAY 0.617021 (3050 2325);
PAINT SKYBLUE (3050 2325);
FORCEPROP 1 LAST VOLTAGE 50V
J 0
(3050 2375);
DISPLAY 0.617021 (3050 2375);
PAINT SKYBLUE (3050 2375);
FORCEPROP 1 LAST VALUE 1000PF
J 0
(3050 2425);
DISPLAY 0.617021 (3050 2425);
PAINT SKYBLUE (3050 2425);
FORCEPROP 1 LAST PACK_TYPE 0402LF
J 0
(3050 2175);
DISPLAY 0.617021 (3050 2175);
PAINT SKYBLUE (3050 2175);
FORCEPROP 2 LAST SEC_TYPE 0402LF
J 0
(3050 2575);
DISPLAY 1.021277 (3050 2575);
PAINT ORANGE (3050 2575);
DISPLAY INVISIBLE (3050 2575);
FORCEPROP 0 LAST SEC 1
J 0
(3050 2475);
DISPLAY 0.680851 (3050 2475);
PAINT MONO (3050 2475);
DISPLAY INVISIBLE (3050 2475);
FORCEPROP 0 LAST ROOM VDDQ_KLM_PWR_VR
J 0
(3050 2575);
DISPLAY 1.021277 (3050 2575);
PAINT ORANGE (3050 2575);
DISPLAY INVISIBLE (3050 2575);
FORCEPROP 1 LAST PATH I118
J 0
(3050 2525);
DISPLAY 0.978723 (3050 2525);
PAINT WHITE (3050 2525);
DISPLAY INVISIBLE (3050 2525);
FORCEPROP 2 LAST CDS_LIB mstr_discrete
J 0
(3000 2375);
PAINT MONO (3000 2375);
DISPLAY INVISIBLE (3000 2375);
FORCEADD GND..1
(2900 -1050);
FORCEPROP 3 LASTPIN (2900 -1000) SIG_NAME GND\g
J 0
(2910 -990);
DISPLAY 0.659574 (2910 -990);
PAINT MONO (2910 -990);
DISPLAY INVISIBLE (2910 -990);
FORCEPROP 1 LAST HDL_POWER GND
J 0
(2900 -900);
DISPLAY 1.723404 (2900 -900);
PAINT GREEN (2900 -900);
DISPLAY INVISIBLE (2900 -900);
FORCEPROP 1 LAST BODY_TYPE PLUMBING
J 0
(2855 -1093);
DISPLAY 0.340426 (2855 -1093);
PAINT GREEN (2855 -1093);
DISPLAY INVISIBLE (2855 -1093);
FORCEPROP 2 LAST CDS_LIB mstr_symbols
J 0
(2900 -1050);
PAINT MONO (2900 -1050);
DISPLAY INVISIBLE (2900 -1050);
FORCEPROP 1 LAST PATH I120
J 0
(2975 -1050);
DISPLAY 0.872340 (2975 -1050);
PAINT AQUA (2975 -1050);
DISPLAY INVISIBLE (2975 -1050);
FORCEPROP 2 LAST ROOM PVCCIN_CPU0_PWR_VR
J 0
(2350 -975);
DISPLAY 1.936170 (2350 -975);
PAINT ORANGE (2350 -975);
DISPLAY INVISIBLE (2350 -975);
FORCEPROP 2 LAST BOM_COST PROC_VRD_VCCIN_CPU0
J 0
(2525 -975);
DISPLAY 1.446809 (2525 -975);
PAINT MONO (2525 -975);
DISPLAY INVISIBLE (2525 -975);
FORCEPROP 1 LAST VOLTAGE 0
J 0
(2900 -1050);
PAINT SKYBLUE (2900 -1050);
DISPLAY INVISIBLE (2900 -1050);
FORCEPROP 1 LAST SIZE 1B
J 0
(2975 -1100);
DISPLAY 1.723404 (2975 -1100);
PAINT GREEN (2975 -1100);
DISPLAY INVISIBLE (2975 -1100);
FORCEADD CAP..1
(2900 -75);
FORCEPROP 0 LAST POP NOPOP
J 0
(2725 -150);
DISPLAY 0.638298 (2725 -150);
PAINT RED (2725 -150);
FORCEPROP 1 LAST LOCATION CT54
J 0
(2750 -75);
DISPLAY 0.617021 (2750 -75);
PAINT AQUA (2750 -75);
FORCEPROP 1 LASTPIN (2900 -175) $PN 2
J 0
(2910 -195);
DISPLAY 0.787234 (2910 -195);
PAINT ORANGE (2910 -195);
FORCEPROP 1 LAST VOLTAGE 50V
J 0
(2950 -75);
DISPLAY 0.617021 (2950 -75);
PAINT SKYBLUE (2950 -75);
FORCEPROP 1 LAST TOLERANCE 10%
J 0
(2950 -125);
DISPLAY 0.617021 (2950 -125);
PAINT SKYBLUE (2950 -125);
FORCEPROP 1 LAST MATERIAL X7R
J 0
(2950 -175);
DISPLAY 0.617021 (2950 -175);
PAINT SKYBLUE (2950 -175);
FORCEPROP 1 LAST PACK_TYPE 0402LF
J 0
(2950 -275);
DISPLAY 0.617021 (2950 -275);
PAINT SKYBLUE (2950 -275);
FORCEPROP 1 LAST PART_NUMBER A36096-046
J 0
(2950 -225);
DISPLAY 0.617021 (2950 -225);
PAINT BLUE (2950 -225);
FORCEPROP 0 LAST BOM_SS NOPOP
J 0
(3200 -275);
DISPLAY 0.638298 (3200 -275);
PAINT BROWN (3200 -275);
DISPLAY BOTH (3200 -275);
FORCEPROP 1 LAST VALUE 1000PF
J 0
(2950 -25);
DISPLAY 0.617021 (2950 -25);
PAINT SKYBLUE (2950 -25);
FORCEPROP 1 LASTPIN (2900 25) $PN 1
J 0
(2910 5);
DISPLAY 0.787234 (2910 5);
PAINT ORANGE (2910 5);
FORCEPROP 2 LAST SEC_TYPE 0402LF
J 0
(2950 125);
DISPLAY 1.021277 (2950 125);
PAINT ORANGE (2950 125);
DISPLAY INVISIBLE (2950 125);
FORCEPROP 0 LAST SEC 1
J 0
(2950 25);
DISPLAY 0.680851 (2950 25);
PAINT MONO (2950 25);
DISPLAY INVISIBLE (2950 25);
FORCEPROP 0 LAST ROOM VDDQ_KLM_PWR_VR
J 0
(2950 125);
DISPLAY 1.021277 (2950 125);
PAINT ORANGE (2950 125);
DISPLAY INVISIBLE (2950 125);
FORCEPROP 1 LAST PATH I121
J 0
(2950 75);
DISPLAY 0.978723 (2950 75);
PAINT WHITE (2950 75);
DISPLAY INVISIBLE (2950 75);
FORCEPROP 2 LAST CDS_LIB mstr_discrete
J 0
(2900 -75);
PAINT MONO (2900 -75);
DISPLAY INVISIBLE (2900 -75);
FORCEADD GND..1
(2900 -275);
FORCEPROP 3 LASTPIN (2900 -225) SIG_NAME GND\g
J 0
(2910 -215);
DISPLAY 0.659574 (2910 -215);
PAINT MONO (2910 -215);
DISPLAY INVISIBLE (2910 -215);
FORCEPROP 1 LAST HDL_POWER GND
J 0
(2900 -125);
DISPLAY 1.170213 (2900 -125);
PAINT GREEN (2900 -125);
DISPLAY INVISIBLE (2900 -125);
FORCEPROP 1 LAST BODY_TYPE PLUMBING
J 0
(2855 -318);
DISPLAY 0.340426 (2855 -318);
PAINT GREEN (2855 -318);
DISPLAY INVISIBLE (2855 -318);
FORCEPROP 1 LAST SIZE 1B
J 0
(2975 -325);
DISPLAY 1.170213 (2975 -325);
PAINT AQUA (2975 -325);
DISPLAY INVISIBLE (2975 -325);
FORCEPROP 1 LAST VOLTAGE 0
J 0
(2900 -275);
PAINT SKYBLUE (2900 -275);
DISPLAY INVISIBLE (2900 -275);
FORCEPROP 2 LAST ROOM VDDQ_KLM_PWR_VR
J 0
(2325 -200);
DISPLAY 1.361702 (2325 -200);
PAINT ORANGE (2325 -200);
DISPLAY INVISIBLE (2325 -200);
FORCEPROP 1 LAST PATH I122
J 0
(2975 -275);
DISPLAY 0.872340 (2975 -275);
PAINT AQUA (2975 -275);
DISPLAY INVISIBLE (2975 -275);
FORCEPROP 2 LAST CDS_LIB mstr_symbols
J 0
(2900 -275);
PAINT MONO (2900 -275);
DISPLAY INVISIBLE (2900 -275);
FORCEADD CAP..1
R 2
(-800 -425);
FORCEPROP 1 LAST PART_NUMBER A36096-104
J 2
(-850 -575);
DISPLAY 0.617021 (-850 -575);
PAINT BLUE (-850 -575);
FORCEPROP 1 LAST VALUE 0.220UF
J 2
(-850 -375);
DISPLAY 0.617021 (-850 -375);
PAINT SKYBLUE (-850 -375);
FORCEPROP 1 LASTPIN (-800 -525) $PN 2
J 2
(-810 -545);
DISPLAY 0.617021 (-810 -545);
PAINT ORANGE (-810 -545);
FORCEPROP 1 LAST PACK_TYPE 0402
J 2
(-850 -625);
DISPLAY 0.617021 (-850 -625);
PAINT SKYBLUE (-850 -625);
FORCEPROP 1 LAST MATERIAL X7R
J 2
(-850 -525);
DISPLAY 0.617021 (-850 -525);
PAINT SKYBLUE (-850 -525);
FORCEPROP 1 LAST TOLERANCE 10%
J 2
(-850 -475);
DISPLAY 0.617021 (-850 -475);
PAINT SKYBLUE (-850 -475);
FORCEPROP 1 LASTPIN (-800 -325) $PN 1
J 2
(-810 -345);
DISPLAY 0.617021 (-810 -345);
PAINT ORANGE (-810 -345);
FORCEPROP 1 LAST VOLTAGE 16V
J 2
(-850 -425);
DISPLAY 0.617021 (-850 -425);
PAINT SKYBLUE (-850 -425);
FORCEPROP 1 LAST LOCATION C7G38
J 2
(-850 -325);
DISPLAY 0.617021 (-850 -325);
PAINT AQUA (-850 -325);
FORCEPROP 0 LAST BOM_SS NOPOP
J 0
(-700 -475);
DISPLAY 0.638298 (-700 -475);
PAINT BROWN (-700 -475);
DISPLAY BOTH (-700 -475);
FORCEPROP 1 LAST PATH I128
J 2
(-850 -275);
DISPLAY 0.978723 (-850 -275);
PAINT WHITE (-850 -275);
DISPLAY INVISIBLE (-850 -275);
FORCEPROP 2 LAST CDS_LIB mstr_discrete
J 0
(-800 -425);
PAINT ORANGE (-800 -425);
DISPLAY INVISIBLE (-800 -425);
FORCEPROP 2 LAST SEC_TYPE 0402
J 0
(-850 -225);
DISPLAY 1.021277 (-850 -225);
PAINT ORANGE (-850 -225);
DISPLAY INVISIBLE (-850 -225);
FORCEPROP 0 LAST SPOF TRUE
J 0
(-850 -225);
DISPLAY 1.021277 (-850 -225);
PAINT ORANGE (-850 -225);
DISPLAY INVISIBLE (-850 -225);
FORCEPROP 2 LAST SEC 1
J 0
(-850 -225);
DISPLAY 0.680851 (-850 -225);
PAINT MONO (-850 -225);
DISPLAY INVISIBLE (-850 -225);
FORCEPROP 2 LAST CDS_LOCATION C7G38
J 2
(-850 -325);
DISPLAY 0.617021 (-850 -325);
PAINT AQUA (-850 -325);
DISPLAY INVISIBLE (-850 -325);
FORCEPROP 2 LAST ROOM VDDQ_ABC_PWR_VR
J 0
(-850 -275);
DISPLAY 1.361702 (-850 -275);
PAINT ORANGE (-850 -275);
DISPLAY INVISIBLE (-850 -275);
FORCEPROP 0 LAST CDS_SEC 1
J 0
(-850 -275);
PAINT MONO (-850 -275);
DISPLAY INVISIBLE (-850 -275);
FORCEADD CAP..1
(2900 1850);
FORCEPROP 1 LASTPIN (2900 1750) $PN 2
J 0
(2910 1730);
DISPLAY 0.787234 (2910 1730);
PAINT ORANGE (2910 1730);
FORCEPROP 1 LAST MATERIAL X7R
J 0
(2950 1750);
DISPLAY 0.617021 (2950 1750);
PAINT SKYBLUE (2950 1750);
FORCEPROP 1 LASTPIN (2900 1950) $PN 1
J 0
(2910 1930);
DISPLAY 0.787234 (2910 1930);
PAINT ORANGE (2910 1930);
FORCEPROP 1 LAST LOCATION CT50
J 0
(2950 1950);
DISPLAY 0.617021 (2950 1950);
PAINT AQUA (2950 1950);
FORCEPROP 1 LAST TOLERANCE 10%
J 0
(2950 1800);
DISPLAY 0.617021 (2950 1800);
PAINT SKYBLUE (2950 1800);
FORCEPROP 1 LAST VOLTAGE 50V
J 0
(2950 1850);
DISPLAY 0.617021 (2950 1850);
PAINT SKYBLUE (2950 1850);
FORCEPROP 1 LAST VALUE 1000PF
J 0
(2950 1900);
DISPLAY 0.617021 (2950 1900);
PAINT SKYBLUE (2950 1900);
FORCEPROP 0 LAST POP NOPOP
J 0
(3100 1800);
DISPLAY 0.808511 (3100 1800);
PAINT RED (3100 1800);
FORCEPROP 1 LAST PACK_TYPE 0402LF
J 0
(3100 1850);
DISPLAY 0.617021 (3100 1850);
PAINT SKYBLUE (3100 1850);
FORCEPROP 1 LAST PART_NUMBER A36096-046
J 0
(3100 1900);
DISPLAY 0.617021 (3100 1900);
PAINT BLUE (3100 1900);
FORCEPROP 2 LAST SEC_TYPE 0402LF
J 0
(2950 2050);
DISPLAY 1.021277 (2950 2050);
PAINT ORANGE (2950 2050);
DISPLAY INVISIBLE (2950 2050);
FORCEPROP 0 LAST SEC 1
J 0
(2950 2000);
DISPLAY 0.680851 (2950 2000);
PAINT MONO (2950 2000);
DISPLAY INVISIBLE (2950 2000);
FORCEPROP 0 LAST ROOM VDDQ_KLM_PWR_VR
J 0
(2950 2050);
DISPLAY 1.021277 (2950 2050);
PAINT ORANGE (2950 2050);
DISPLAY INVISIBLE (2950 2050);
FORCEPROP 1 LAST PATH I135
J 0
(2950 2000);
DISPLAY 0.978723 (2950 2000);
PAINT WHITE (2950 2000);
DISPLAY INVISIBLE (2950 2000);
FORCEPROP 2 LAST CDS_LIB mstr_discrete
J 0
(2900 1850);
PAINT MONO (2900 1850);
DISPLAY INVISIBLE (2900 1850);
FORCEADD CAP..1
(2900 -525);
FORCEPROP 1 LASTPIN (2900 -625) $PN 2
J 0
(2910 -645);
DISPLAY 0.787234 (2910 -645);
PAINT ORANGE (2910 -645);
FORCEPROP 1 LAST TOLERANCE 10%
J 0
(2950 -525);
DISPLAY 0.617021 (2950 -525);
PAINT SKYBLUE (2950 -525);
FORCEPROP 1 LASTPIN (2900 -425) $PN 1
J 0
(2910 -445);
DISPLAY 0.787234 (2910 -445);
PAINT ORANGE (2910 -445);
FORCEPROP 1 LAST LOCATION CT53
J 0
(2950 -475);
DISPLAY 0.617021 (2950 -475);
PAINT AQUA (2950 -475);
FORCEPROP 1 LAST PART_NUMBER A36096-046
J 0
(2950 -575);
DISPLAY 0.617021 (2950 -575);
PAINT BLUE (2950 -575);
FORCEPROP 0 LAST POP NOPOP
J 0
(2950 -625);
DISPLAY 0.638298 (2950 -625);
PAINT RED (2950 -625);
FORCEPROP 1 LAST MATERIAL X7R
J 0
(3050 -525);
DISPLAY 0.617021 (3050 -525);
PAINT SKYBLUE (3050 -525);
FORCEPROP 1 LAST PACK_TYPE 0402LF
J 0
(3175 -575);
DISPLAY 0.617021 (3175 -575);
PAINT SKYBLUE (3175 -575);
FORCEPROP 0 LAST BOM_SS NOPOP
J 0
(3150 -625);
DISPLAY 0.638298 (3150 -625);
PAINT BROWN (3150 -625);
DISPLAY BOTH (3150 -625);
FORCEPROP 1 LAST VALUE 1000PF
J 0
(3075 -475);
DISPLAY 0.617021 (3075 -475);
PAINT SKYBLUE (3075 -475);
FORCEPROP 1 LAST VOLTAGE 50V
J 0
(3250 -475);
DISPLAY 0.617021 (3250 -475);
PAINT SKYBLUE (3250 -475);
FORCEPROP 2 LAST CDS_LIB mstr_discrete
J 0
(2900 -525);
PAINT MONO (2900 -525);
DISPLAY INVISIBLE (2900 -525);
FORCEPROP 1 LAST PATH I136
J 0
(2950 -375);
DISPLAY 0.978723 (2950 -375);
PAINT WHITE (2950 -375);
DISPLAY INVISIBLE (2950 -375);
FORCEPROP 0 LAST ROOM VDDQ_KLM_PWR_VR
J 0
(2950 -325);
DISPLAY 1.021277 (2950 -325);
PAINT ORANGE (2950 -325);
DISPLAY INVISIBLE (2950 -325);
FORCEPROP 0 LAST SEC 1
J 0
(2950 -375);
DISPLAY 0.680851 (2950 -375);
PAINT MONO (2950 -375);
DISPLAY INVISIBLE (2950 -375);
FORCEPROP 2 LAST SEC_TYPE 0402LF
J 0
(2950 -325);
DISPLAY 1.021277 (2950 -325);
PAINT ORANGE (2950 -325);
DISPLAY INVISIBLE (2950 -325);
FORCEADD RES..1
(125 2075);
FORCEPROP 1 LAST LOCATION RT33
J 0
(-50 2125);
DISPLAY 0.617021 (-50 2125);
PAINT AQUA (-50 2125);
FORCEPROP 1 LAST WATTAGE 1/10W
J 2
(100 1925);
DISPLAY 0.617021 (100 1925);
PAINT SKYBLUE (100 1925);
FORCEPROP 1 LAST PART_NUMBER G22178-002
J 0
(50 1975);
DISPLAY 0.617021 (50 1975);
PAINT BLUE (50 1975);
FORCEPROP 1 LAST TOLERANCE 5.0%
J 0
(125 1875);
DISPLAY 0.617021 (125 1875);
PAINT SKYBLUE (125 1875);
FORCEPROP 1 LAST MATERIAL CHIP
J 0
(125 1925);
DISPLAY 0.617021 (125 1925);
PAINT SKYBLUE (125 1925);
FORCEPROP 1 LAST PACK_TYPE 0603
J 0
(200 2025);
DISPLAY 0.617021 (200 2025);
PAINT SKYBLUE (200 2025);
FORCEPROP 1 LAST VALUE 0
J 2
(75 2025);
DISPLAY 0.617021 (75 2025);
PAINT SKYBLUE (75 2025);
FORCEPROP 1 LASTPIN (25 2075) $PN 1
J 0
(37 2087);
DISPLAY 0.787234 (37 2087);
PAINT ORANGE (37 2087);
FORCEPROP 1 LASTPIN (225 2075) $PN 2
J 0
(187 2087);
DISPLAY 0.787234 (187 2087);
PAINT ORANGE (187 2087);
FORCEPROP 2 LAST SEC_TYPE 0603
J 0
(75 2275);
DISPLAY 1.021277 (75 2275);
PAINT ORANGE (75 2275);
DISPLAY INVISIBLE (75 2275);
FORCEPROP 0 LAST SEC 1
J 0
(-125 2175);
DISPLAY 0.680851 (-125 2175);
PAINT MONO (-125 2175);
DISPLAY INVISIBLE (-125 2175);
FORCEPROP 0 LAST BOM_COST NT_GBE_BASE
J 0
(225 2300);
DISPLAY 1.021277 (225 2300);
PAINT ORANGE (225 2300);
DISPLAY INVISIBLE (225 2300);
FORCEPROP 0 LAST ROOM NIC_SPRV
J 0
(225 2200);
DISPLAY 1.021277 (225 2200);
PAINT ORANGE (225 2200);
DISPLAY INVISIBLE (225 2200);
FORCEPROP 1 LAST PATH I139
J 0
(75 2225);
DISPLAY 0.978723 (75 2225);
PAINT WHITE (75 2225);
DISPLAY INVISIBLE (75 2225);
FORCEPROP 2 LAST CDS_LIB mstr_discrete
J 0
(125 2075);
PAINT MONO (125 2075);
DISPLAY INVISIBLE (125 2075);
FORCEADD RES..1
(100 -275);
FORCEPROP 1 LAST PART_NUMBER G22178-002
J 0
(0 -425);
DISPLAY 0.617021 (0 -425);
PAINT BLUE (0 -425);
FORCEPROP 1 LAST LOCATION RT36
J 0
(25 -325);
DISPLAY 0.617021 (25 -325);
PAINT AQUA (25 -325);
FORCEPROP 1 LAST PACK_TYPE 0603
J 0
(25 -375);
DISPLAY 0.617021 (25 -375);
PAINT SKYBLUE (25 -375);
FORCEPROP 1 LAST VALUE 0
J 2
(200 -325);
DISPLAY 0.617021 (200 -325);
PAINT SKYBLUE (200 -325);
FORCEPROP 1 LASTPIN (0 -275) $PN 1
J 0
(12 -263);
DISPLAY 0.787234 (12 -263);
PAINT ORANGE (12 -263);
FORCEPROP 1 LASTPIN (200 -275) $PN 2
J 0
(162 -263);
DISPLAY 0.787234 (162 -263);
PAINT ORANGE (162 -263);
FORCEPROP 1 LAST TOLERANCE 5.0%
J 0
(300 -325);
DISPLAY 0.617021 (300 -325);
PAINT SKYBLUE (300 -325);
FORCEPROP 1 LAST WATTAGE 1/10W
J 2
(425 -425);
DISPLAY 0.617021 (425 -425);
PAINT SKYBLUE (425 -425);
FORCEPROP 1 LAST MATERIAL CHIP
J 0
(300 -375);
DISPLAY 0.617021 (300 -375);
PAINT SKYBLUE (300 -375);
FORCEPROP 0 LAST BOM_SS NOPOP
J 0
(450 -325);
DISPLAY 0.638298 (450 -325);
PAINT BROWN (450 -325);
DISPLAY BOTH (450 -325);
FORCEPROP 2 LAST SEC_TYPE 0603
J 0
(50 -75);
DISPLAY 1.021277 (50 -75);
PAINT ORANGE (50 -75);
DISPLAY INVISIBLE (50 -75);
FORCEPROP 0 LAST SEC 1
J 0
(-150 -175);
DISPLAY 0.680851 (-150 -175);
PAINT MONO (-150 -175);
DISPLAY INVISIBLE (-150 -175);
FORCEPROP 0 LAST ROOM NIC_SPRV
J 0
(200 -150);
DISPLAY 1.021277 (200 -150);
PAINT ORANGE (200 -150);
DISPLAY INVISIBLE (200 -150);
FORCEPROP 0 LAST BOM_COST NT_GBE_BASE
J 0
(200 -50);
DISPLAY 1.021277 (200 -50);
PAINT ORANGE (200 -50);
DISPLAY INVISIBLE (200 -50);
FORCEPROP 1 LAST PATH I140
J 0
(50 -125);
DISPLAY 0.978723 (50 -125);
PAINT WHITE (50 -125);
DISPLAY INVISIBLE (50 -125);
FORCEPROP 2 LAST CDS_LIB mstr_discrete
J 0
(100 -275);
PAINT MONO (100 -275);
DISPLAY INVISIBLE (100 -275);
FORCEADD RES..1
(-575 3100);
FORCEPROP 1 LAST TOLERANCE 5%
J 0
(-625 3000);
DISPLAY 0.617021 (-625 3000);
PAINT SKYBLUE (-625 3000);
FORCEPROP 1 LAST VALUE 0.0
J 2
(-675 3000);
DISPLAY 0.617021 (-675 3000);
PAINT SKYBLUE (-675 3000);
FORCEPROP 1 LAST PACK_TYPE 0402
J 0
(-500 3000);
DISPLAY 0.617021 (-500 3000);
PAINT SKYBLUE (-500 3000);
FORCEPROP 1 LAST MATERIAL CHIP
J 0
(-375 3000);
DISPLAY 0.510638 (-375 3000);
PAINT SKYBLUE (-375 3000);
FORCEPROP 1 LAST PART_NUMBER G21497-005
J 0
(-700 3050);
DISPLAY 0.617021 (-700 3050);
PAINT BLUE (-700 3050);
FORCEPROP 1 LAST LOCATION R3U6
J 0
(-675 3150);
DISPLAY 0.617021 (-675 3150);
PAINT AQUA (-675 3150);
FORCEPROP 1 LASTPIN (-675 3100) $PN 1
J 0
(-663 3112);
DISPLAY 0.617021 (-663 3112);
PAINT WHITE (-663 3112);
FORCEPROP 1 LASTPIN (-475 3100) $PN 2
J 0
(-513 3112);
DISPLAY 0.617021 (-513 3112);
PAINT WHITE (-513 3112);
FORCEPROP 1 LAST WATTAGE 1/16W
J 2
(-250 3125);
DISPLAY 0.510638 (-250 3125);
PAINT SKYBLUE (-250 3125);
FORCEPROP 1 LAST PATH I145
J 0
(-625 3250);
DISPLAY 0.978723 (-625 3250);
PAINT WHITE (-625 3250);
DISPLAY INVISIBLE (-625 3250);
FORCEPROP 2 LAST BOM_COST PROC_SIDEBAND
J 0
(-575 3100);
PAINT MONO (-575 3100);
DISPLAY INVISIBLE (-575 3100);
FORCEPROP 2 LAST CDS_LIB mstr_discrete
J 0
(-575 3100);
DISPLAY 1.340426 (-575 3100);
PAINT ORANGE (-575 3100);
DISPLAY INVISIBLE (-575 3100);
FORCEPROP 2 LAST SEC_TYPE 0402
J 0
(-625 3325);
DISPLAY 1.021277 (-625 3325);
PAINT ORANGE (-625 3325);
DISPLAY INVISIBLE (-625 3325);
FORCEPROP 2 LAST SEC 1
J 0
(-625 3325);
DISPLAY 0.680851 (-625 3325);
PAINT MONO (-625 3325);
DISPLAY INVISIBLE (-625 3325);
FORCEPROP 2 LAST ROOM CPU0
J 0
(-625 3250);
PAINT PEACH (-625 3250);
DISPLAY INVISIBLE (-625 3250);
FORCEPROP 0 LAST CDS_SEC 1
J 0
(-275 3150);
PAINT MONO (-275 3150);
DISPLAY INVISIBLE (-275 3150);
FORCEPROP 2 LAST CDS_LOCATION R3U6
J 0
(-1050 3100);
DISPLAY 0.617021 (-1050 3100);
PAINT AQUA (-1050 3100);
DISPLAY INVISIBLE (-1050 3100);
FORCEADD RES..1
(-600 725);
FORCEPROP 1 LAST VALUE 0.0
J 2
(-700 625);
DISPLAY 0.617021 (-700 625);
PAINT SKYBLUE (-700 625);
FORCEPROP 1 LASTPIN (-700 725) $PN 1
J 0
(-688 737);
DISPLAY 0.617021 (-688 737);
PAINT WHITE (-688 737);
FORCEPROP 1 LAST TOLERANCE 5%
J 0
(-650 625);
DISPLAY 0.617021 (-650 625);
PAINT SKYBLUE (-650 625);
FORCEPROP 1 LAST LOCATION R3U9
J 0
(-700 775);
DISPLAY 0.617021 (-700 775);
PAINT AQUA (-700 775);
FORCEPROP 1 LAST PACK_TYPE 0402
J 0
(-525 625);
DISPLAY 0.617021 (-525 625);
PAINT SKYBLUE (-525 625);
FORCEPROP 0 LAST BOM_SS NOPOP
J 0
(-775 525);
DISPLAY 0.638298 (-775 525);
PAINT BROWN (-775 525);
DISPLAY BOTH (-775 525);
FORCEPROP 1 LAST PART_NUMBER G21497-005
J 0
(-725 675);
DISPLAY 0.617021 (-725 675);
PAINT BLUE (-725 675);
FORCEPROP 1 LASTPIN (-500 725) $PN 2
J 0
(-538 737);
DISPLAY 0.617021 (-538 737);
PAINT WHITE (-538 737);
FORCEPROP 1 LAST MATERIAL CHIP
J 0
(-400 625);
DISPLAY 0.510638 (-400 625);
PAINT SKYBLUE (-400 625);
FORCEPROP 1 LAST WATTAGE 1/16W
J 2
(-275 775);
DISPLAY 0.510638 (-275 775);
PAINT SKYBLUE (-275 775);
FORCEPROP 2 LAST CDS_LOCATION R3U9
J 0
(-1075 725);
DISPLAY 0.617021 (-1075 725);
PAINT AQUA (-1075 725);
DISPLAY INVISIBLE (-1075 725);
FORCEPROP 1 LAST PATH I146
J 0
(-650 875);
DISPLAY 0.978723 (-650 875);
PAINT WHITE (-650 875);
DISPLAY INVISIBLE (-650 875);
FORCEPROP 2 LAST BOM_COST PROC_SIDEBAND
J 0
(-600 725);
PAINT MONO (-600 725);
DISPLAY INVISIBLE (-600 725);
FORCEPROP 2 LAST CDS_LIB mstr_discrete
J 0
(-600 725);
DISPLAY 1.340426 (-600 725);
PAINT ORANGE (-600 725);
DISPLAY INVISIBLE (-600 725);
FORCEPROP 2 LAST SEC_TYPE 0402
J 0
(-650 950);
DISPLAY 1.021277 (-650 950);
PAINT ORANGE (-650 950);
DISPLAY INVISIBLE (-650 950);
FORCEPROP 2 LAST SEC 1
J 0
(-650 950);
DISPLAY 0.680851 (-650 950);
PAINT MONO (-650 950);
DISPLAY INVISIBLE (-650 950);
FORCEPROP 2 LAST ROOM CPU0
J 0
(-650 875);
PAINT PEACH (-650 875);
DISPLAY INVISIBLE (-650 875);
FORCEPROP 0 LAST CDS_SEC 1
J 0
(-300 775);
PAINT MONO (-300 775);
DISPLAY INVISIBLE (-300 775);
FORCEADD SC1U10V2KX-4-GP..1
(-250 2525);
FORCEPROP 2 LASTPIN (-250 2450) $PN 2
R 1
J 2
(-260 2440);
DISPLAY 0.808511 (-260 2440);
PAINT ORANGE (-260 2440);
FORCEPROP 2 LAST RATED 10V
J 0
(-125 2450);
DISPLAY 0.638298 (-125 2450);
PAINT GREEN (-125 2450);
FORCEPROP 2 LAST PACK_SIZE 0402
J 0
(-125 2400);
DISPLAY 0.638298 (-125 2400);
PAINT GREEN (-125 2400);
FORCEPROP 2 LAST TOLERANCE 10%
J 0
(-125 2500);
DISPLAY 0.638298 (-125 2500);
PAINT GREEN (-125 2500);
FORCEPROP 2 LAST ATTRIBUTE 1UF
J 0
(-125 2550);
DISPLAY 0.638298 (-125 2550);
PAINT GREEN (-125 2550);
FORCEPROP 1 LAST VALUE SC1U10V2KX-4-GP
R 1
J 0
(-150 2300);
DISPLAY 0.617021 (-150 2300);
PAINT GREEN (-150 2300);
FORCEPROP 2 LASTPIN (-250 2600) $PN 1
R 1
J 0
(-260 2610);
DISPLAY 0.808511 (-260 2610);
PAINT ORANGE (-260 2610);
FORCEPROP 1 LAST LOCATION C7G35
J 0
(-125 2605);
DISPLAY 0.617021 (-125 2605);
PAINT GREEN (-125 2605);
FORCEPROP 1 LAST PACK_TYPE SMD-BCG6
J 0
(-250 2525);
DISPLAY 0.617021 (-250 2525);
PAINT GREEN (-250 2525);
DISPLAY INVISIBLE (-250 2525);
FORCEPROP 2 LAST SEC 1
J 0
(-225 2600);
DISPLAY 0.680851 (-225 2600);
PAINT MONO (-225 2600);
DISPLAY INVISIBLE (-225 2600);
FORCEPROP 2 LAST SEC_TYPE SMD-BCG6
J 0
(-225 2600);
DISPLAY 1.021277 (-225 2600);
PAINT ORANGE (-225 2600);
DISPLAY INVISIBLE (-225 2600);
FORCEPROP 1 LAST PART_NUMBER 78.10523.8FL
J 0
(-250 2525);
DISPLAY 0.617021 (-250 2525);
PAINT GREEN (-250 2525);
DISPLAY INVISIBLE (-250 2525);
FORCEPROP 2 LAST CDS_LIB w_hdl
J 0
(-250 2525);
PAINT MONO (-250 2525);
DISPLAY INVISIBLE (-250 2525);
FORCEPROP 1 LAST PATH I149
J 0
(-250 2525);
DISPLAY 0.617021 (-250 2525);
PAINT GREEN (-250 2525);
DISPLAY INVISIBLE (-250 2525);
FORCEPROP 1 LAST CDS_LMAN_SYM_OUTLINE -50,25,50,-25
J 0
(-250 2525);
DISPLAY 0.468085 (-250 2525);
PAINT GREEN (-250 2525);
DISPLAY INVISIBLE (-250 2525);
FORCEADD SC1U10V2KX-4-GP..1
(-325 175);
FORCEPROP 1 LAST VALUE SC1U10V2KX-4-GP
R 1
J 0
(-225 -50);
DISPLAY 0.617021 (-225 -50);
PAINT GREEN (-225 -50);
FORCEPROP 2 LASTPIN (-325 100) $PN 2
R 1
J 2
(-335 90);
DISPLAY 0.808511 (-335 90);
PAINT ORANGE (-335 90);
FORCEPROP 2 LASTPIN (-325 250) $PN 1
R 1
J 0
(-335 260);
DISPLAY 0.808511 (-335 260);
PAINT ORANGE (-335 260);
FORCEPROP 2 LAST TOLERANCE 10%
J 0
(-200 150);
DISPLAY 0.638298 (-200 150);
PAINT GREEN (-200 150);
FORCEPROP 2 LAST PACK_SIZE 0402
J 0
(-200 50);
DISPLAY 0.638298 (-200 50);
PAINT GREEN (-200 50);
FORCEPROP 2 LAST RATED 10V
J 0
(-200 100);
DISPLAY 0.638298 (-200 100);
PAINT GREEN (-200 100);
FORCEPROP 2 LAST ATTRIBUTE 1UF
J 0
(-200 200);
DISPLAY 0.638298 (-200 200);
PAINT GREEN (-200 200);
FORCEPROP 1 LAST LOCATION C7G42
J 0
(-200 255);
DISPLAY 0.617021 (-200 255);
PAINT GREEN (-200 255);
FORCEPROP 0 LAST BOM_SS NOPOP
J 0
(-200 0);
DISPLAY 0.638298 (-200 0);
PAINT BROWN (-200 0);
DISPLAY BOTH (-200 0);
FORCEPROP 1 LAST CDS_LMAN_SYM_OUTLINE -50,25,50,-25
J 0
(-325 175);
DISPLAY 0.468085 (-325 175);
PAINT GREEN (-325 175);
DISPLAY INVISIBLE (-325 175);
FORCEPROP 1 LAST PATH I150
J 0
(-325 175);
DISPLAY 0.617021 (-325 175);
PAINT GREEN (-325 175);
DISPLAY INVISIBLE (-325 175);
FORCEPROP 2 LAST CDS_LIB w_hdl
J 0
(-325 175);
PAINT MONO (-325 175);
DISPLAY INVISIBLE (-325 175);
FORCEPROP 1 LAST PART_NUMBER 78.10523.8FL
J 0
(-325 175);
DISPLAY 0.617021 (-325 175);
PAINT GREEN (-325 175);
DISPLAY INVISIBLE (-325 175);
FORCEPROP 2 LAST SEC_TYPE SMD-BCG6
J 0
(-300 250);
DISPLAY 1.021277 (-300 250);
PAINT ORANGE (-300 250);
DISPLAY INVISIBLE (-300 250);
FORCEPROP 2 LAST SEC 1
J 0
(-300 250);
DISPLAY 0.680851 (-300 250);
PAINT MONO (-300 250);
DISPLAY INVISIBLE (-300 250);
FORCEPROP 1 LAST PACK_TYPE SMD-BCG6
J 0
(-325 175);
DISPLAY 0.617021 (-325 175);
PAINT GREEN (-325 175);
DISPLAY INVISIBLE (-325 175);
FORCEADD 1R3F-GP..1
(2900 1500);
FORCEPROP 2 LASTPIN (2900 1375) $PN 2
R 1
J 2
(2890 1365);
DISPLAY 0.808511 (2890 1365);
PAINT ORANGE (2890 1365);
FORCEPROP 2 LAST TOLERANCE 1%
J 0
(2950 1475);
DISPLAY 0.638298 (2950 1475);
PAINT GREEN (2950 1475);
FORCEPROP 2 LAST PACK_SIZE 0603
J 0
(2950 1375);
DISPLAY 0.638298 (2950 1375);
PAINT GREEN (2950 1375);
FORCEPROP 2 LASTPIN (2900 1625) $PN 1
R 1
J 0
(2890 1635);
DISPLAY 0.808511 (2890 1635);
PAINT ORANGE (2890 1635);
FORCEPROP 1 LAST LOCATION RT34
J 0
(2950 1625);
DISPLAY 0.617021 (2950 1625);
PAINT GREEN (2950 1625);
FORCEPROP 2 LAST RATED 1/10W
J 0
(2950 1425);
DISPLAY 0.638298 (2950 1425);
PAINT GREEN (2950 1425);
FORCEPROP 1 LAST VALUE 1R3F-GP
J 0
(2950 1575);
DISPLAY 0.617021 (2950 1575);
PAINT GREEN (2950 1575);
FORCEPROP 2 LAST ATTRIBUTE 1 OHM
J 0
(2950 1525);
DISPLAY 0.638298 (2950 1525);
PAINT GREEN (2950 1525);
FORCEPROP 0 LAST POP NOPOP
J 0
(2950 1325);
DISPLAY 0.638298 (2950 1325);
PAINT RED (2950 1325);
FORCEPROP 1 LAST PATH I151
J 0
(2900 1500);
DISPLAY 0.617021 (2900 1500);
PAINT GREEN (2900 1500);
DISPLAY INVISIBLE (2900 1500);
FORCEPROP 1 LAST CDS_LMAN_SYM_OUTLINE -50,75,50,-75
J 0
(2900 1500);
DISPLAY 0.468085 (2900 1500);
PAINT GREEN (2900 1500);
DISPLAY INVISIBLE (2900 1500);
FORCEPROP 2 LAST CDS_LIB w_hdl
J 0
(2900 1500);
DISPLAY INVISIBLE (2900 1500);
FORCEPROP 1 LAST PART_NUMBER 64.1R005.55L
J 0
(2900 1500);
DISPLAY 0.617021 (2900 1500);
PAINT GREEN (2900 1500);
DISPLAY INVISIBLE (2900 1500);
FORCEPROP 2 LAST SEC_TYPE RCL_GP
J 0
(2950 1600);
DISPLAY 1.021277 (2950 1600);
PAINT ORANGE (2950 1600);
DISPLAY INVISIBLE (2950 1600);
FORCEPROP 2 LAST SEC 1
J 0
(2950 1600);
DISPLAY 0.680851 (2950 1600);
PAINT MONO (2950 1600);
DISPLAY INVISIBLE (2950 1600);
FORCEPROP 1 LAST PACK_TYPE RCL_GP
J 0
(2900 1500);
DISPLAY 0.617021 (2900 1500);
PAINT GREEN (2900 1500);
DISPLAY INVISIBLE (2900 1500);
FORCEADD 1R3F-GP..1
(2900 -850);
FORCEPROP 2 LASTPIN (2900 -975) $PN 2
R 1
J 2
(2890 -935);
DISPLAY 0.808511 (2890 -935);
PAINT ORANGE (2890 -935);
FORCEPROP 2 LAST PACK_SIZE 0603
J 0
(2950 -975);
DISPLAY 0.638298 (2950 -975);
PAINT GREEN (2950 -975);
FORCEPROP 2 LAST TOLERANCE 1%
J 0
(2950 -875);
DISPLAY 0.638298 (2950 -875);
PAINT GREEN (2950 -875);
FORCEPROP 2 LASTPIN (2900 -725) $PN 1
R 1
J 0
(2890 -715);
DISPLAY 0.808511 (2890 -715);
PAINT ORANGE (2890 -715);
FORCEPROP 1 LAST LOCATION RT35
J 0
(2950 -725);
DISPLAY 0.617021 (2950 -725);
PAINT GREEN (2950 -725);
FORCEPROP 2 LAST RATED 1/10W
J 0
(2950 -925);
DISPLAY 0.638298 (2950 -925);
PAINT GREEN (2950 -925);
FORCEPROP 2 LAST ATTRIBUTE 1 OHM
J 0
(2950 -825);
DISPLAY 0.638298 (2950 -825);
PAINT GREEN (2950 -825);
FORCEPROP 1 LAST VALUE 1R3F-GP
J 0
(2950 -775);
DISPLAY 0.617021 (2950 -775);
PAINT GREEN (2950 -775);
FORCEPROP 0 LAST POP NOPOP
J 0
(2950 -1025);
DISPLAY 0.638298 (2950 -1025);
PAINT RED (2950 -1025);
FORCEPROP 0 LAST BOM_SS NOPOP
J 0
(3100 -1025);
DISPLAY 0.638298 (3100 -1025);
PAINT BROWN (3100 -1025);
DISPLAY BOTH (3100 -1025);
FORCEPROP 1 LAST PATH I152
J 0
(2900 -850);
DISPLAY 0.617021 (2900 -850);
PAINT GREEN (2900 -850);
DISPLAY INVISIBLE (2900 -850);
FORCEPROP 1 LAST PACK_TYPE RCL_GP
J 0
(2900 -850);
DISPLAY 0.617021 (2900 -850);
PAINT GREEN (2900 -850);
DISPLAY INVISIBLE (2900 -850);
FORCEPROP 2 LAST SEC 1
J 0
(2950 -750);
DISPLAY 0.680851 (2950 -750);
PAINT MONO (2950 -750);
DISPLAY INVISIBLE (2950 -750);
FORCEPROP 2 LAST SEC_TYPE RCL_GP
J 0
(2950 -750);
DISPLAY 1.021277 (2950 -750);
PAINT ORANGE (2950 -750);
DISPLAY INVISIBLE (2950 -750);
FORCEPROP 1 LAST PART_NUMBER 64.1R005.55L
J 0
(2900 -850);
DISPLAY 0.617021 (2900 -850);
PAINT GREEN (2900 -850);
DISPLAY INVISIBLE (2900 -850);
FORCEPROP 2 LAST CDS_LIB w_hdl
J 0
(2900 -850);
DISPLAY INVISIBLE (2900 -850);
FORCEPROP 1 LAST CDS_LMAN_SYM_OUTLINE -50,75,50,-75
J 0
(2900 -850);
DISPLAY 0.468085 (2900 -850);
PAINT GREEN (2900 -850);
DISPLAY INVISIBLE (2900 -850);
FORCEADD IND-120NH-30-GP..1
R 1
(3900 2025);
FORCEPROP 2 LASTPIN (3750 2000) $PN 1
J 2
(3740 2010);
DISPLAY 0.808511 (3740 2010);
PAINT ORANGE (3740 2010);
FORCEPROP 0 LAST DS_VALUE 90NH
J 0
(3700 1725);
DISPLAY 0.638298 (3700 1725);
PAINT BROWN (3700 1725);
DISPLAY BOTH (3700 1725);
FORCEPROP 0 LAST NEW_PACK_SIZE DCR=0.17MOHM
J 0
(3700 1575);
DISPLAY 0.638298 (3700 1575);
PAINT BROWN (3700 1575);
FORCEPROP 1 LAST LOCATION L7G1
J 0
(3750 2075);
DISPLAY 0.617021 (3750 2075);
PAINT GREEN (3750 2075);
FORCEPROP 0 LAST SS_ISAT 94A@25C
J 0
(3700 1825);
DISPLAY 0.638298 (3700 1825);
PAINT BROWN (3700 1825);
DISPLAY BOTH (3700 1825);
FORCEPROP 2 LASTPIN (4050 2000) $PN 2
J 0
(4060 2010);
DISPLAY 0.808511 (4060 2010);
PAINT ORANGE (4060 2010);
FORCEPROP 0 LAST BOM_DS 068.9002N.1021
J 0
(3700 1775);
DISPLAY 0.638298 (3700 1775);
PAINT BROWN (3700 1775);
DISPLAY BOTH (3700 1775);
FORCEPROP 0 LAST NEW_RATED DS_ISAT=134A@25C
J 0
(3700 1675);
DISPLAY 0.638298 (3700 1675);
PAINT BROWN (3700 1675);
FORCEPROP 0 LAST NEW_TYPE IRMS=66A@DELTA_T<40C
J 0
(3700 1625);
DISPLAY 0.638298 (3700 1625);
PAINT BROWN (3700 1625);
FORCEPROP 0 LAST SS_VALUE 120NH
J 0
(3700 1875);
DISPLAY 0.638298 (3700 1875);
PAINT BROWN (3700 1875);
DISPLAY BOTH (3700 1875);
FORCEPROP 0 LAST BOM_SS 068.1202N.M001
J 0
(3700 1925);
DISPLAY 0.638298 (3700 1925);
PAINT BROWN (3700 1925);
DISPLAY BOTH (3700 1925);
FORCEPROP 1 LAST PATH I153
R 1
J 0
(3900 2025);
DISPLAY 0.617021 (3900 2025);
PAINT GREEN (3900 2025);
DISPLAY INVISIBLE (3900 2025);
FORCEPROP 0 LAST TYPE IRMS=66A@DELTA_T<40C
J 0
(3750 1775);
DISPLAY 0.638298 (3750 1775);
PAINT GREEN (3750 1775);
DISPLAY INVISIBLE (3750 1775);
FORCEPROP 0 LAST PACK_SIZE DCR=0.17MOHM
J 0
(3750 1725);
DISPLAY 0.638298 (3750 1725);
PAINT GREEN (3750 1725);
DISPLAY INVISIBLE (3750 1725);
FORCEPROP 0 LAST RATED ISAT=94A@25C
J 0
(3750 1825);
DISPLAY 0.638298 (3750 1825);
PAINT GREEN (3750 1825);
DISPLAY INVISIBLE (3750 1825);
FORCEPROP 0 LAST ATTRIBUTE 120NH
J 0
(3750 1875);
DISPLAY 0.638298 (3750 1875);
PAINT GREEN (3750 1875);
DISPLAY INVISIBLE (3750 1875);
FORCEPROP 1 LAST VALUE IND-120NH-30-GP
J 0
(3750 1925);
DISPLAY 0.617021 (3750 1925);
PAINT GREEN (3750 1925);
DISPLAY INVISIBLE (3750 1925);
FORCEPROP 1 LAST PACK_TYPE DISCRET-GB2
R 1
J 0
(3900 2025);
DISPLAY 0.617021 (3900 2025);
PAINT GREEN (3900 2025);
DISPLAY INVISIBLE (3900 2025);
FORCEPROP 2 LAST SEC 1
J 0
(3775 2100);
DISPLAY 0.680851 (3775 2100);
PAINT MONO (3775 2100);
DISPLAY INVISIBLE (3775 2100);
FORCEPROP 2 LAST SEC_TYPE DISCRET-GB2
J 0
(3775 2100);
DISPLAY 1.021277 (3775 2100);
PAINT ORANGE (3775 2100);
DISPLAY INVISIBLE (3775 2100);
FORCEPROP 1 LAST CDS_LMAN_SYM_OUTLINE -75,100,75,-100
R 1
J 0
(3900 2025);
DISPLAY 0.468085 (3900 2025);
PAINT GREEN (3900 2025);
DISPLAY INVISIBLE (3900 2025);
FORCEPROP 2 LAST CDS_LIB w_hdl
R 1
J 0
(3900 2025);
PAINT MONO (3900 2025);
DISPLAY INVISIBLE (3900 2025);
FORCEPROP 1 LAST PART_NUMBER 068.1202N.M001
R 1
J 0
(3900 2025);
DISPLAY 0.617021 (3900 2025);
PAINT GREEN (3900 2025);
DISPLAY INVISIBLE (3900 2025);
FORCEADD IND-120NH-30-GP..1
R 1
(3950 -350);
FORCEPROP 2 LASTPIN (3800 -375) $PN 1
J 2
(3790 -365);
DISPLAY 0.808511 (3790 -365);
PAINT ORANGE (3790 -365);
FORCEPROP 1 LAST LOCATION L7G2
J 0
(3800 -300);
DISPLAY 0.617021 (3800 -300);
PAINT GREEN (3800 -300);
FORCEPROP 0 LAST NEW_PACK_SIZE DCR=0.17MOHM
J 0
(3750 -700);
DISPLAY 0.638298 (3750 -700);
PAINT BROWN (3750 -700);
FORCEPROP 0 LAST NEW_RATED DS_ISAT=134A@25C
J 0
(3750 -600);
DISPLAY 0.638298 (3750 -600);
PAINT BROWN (3750 -600);
FORCEPROP 0 LAST DS_VALUE 90NH
J 0
(3750 -550);
DISPLAY 0.638298 (3750 -550);
PAINT BROWN (3750 -550);
DISPLAY BOTH (3750 -550);
FORCEPROP 0 LAST BOM_DS 068.9002N.1021
J 0
(3750 -500);
DISPLAY 0.638298 (3750 -500);
PAINT BROWN (3750 -500);
DISPLAY BOTH (3750 -500);
FORCEPROP 0 LAST BOM_SS NOPOP
J 0
(3750 -450);
DISPLAY 0.638298 (3750 -450);
PAINT BROWN (3750 -450);
DISPLAY BOTH (3750 -450);
FORCEPROP 2 LASTPIN (4100 -375) $PN 2
J 0
(4110 -365);
DISPLAY 0.808511 (4110 -365);
PAINT ORANGE (4110 -365);
FORCEPROP 0 LAST NEW_TYPE IRMS=66A@DELTA_T<40C
J 0
(3750 -650);
DISPLAY 0.638298 (3750 -650);
PAINT BROWN (3750 -650);
FORCEPROP 1 LAST PART_NUMBER 068.1202N.M001
R 1
J 0
(3950 -350);
DISPLAY 0.617021 (3950 -350);
PAINT GREEN (3950 -350);
DISPLAY INVISIBLE (3950 -350);
FORCEPROP 2 LAST CDS_LIB w_hdl
R 1
J 0
(3950 -350);
PAINT MONO (3950 -350);
DISPLAY INVISIBLE (3950 -350);
FORCEPROP 1 LAST CDS_LMAN_SYM_OUTLINE -75,100,75,-100
R 1
J 0
(3950 -350);
DISPLAY 0.468085 (3950 -350);
PAINT GREEN (3950 -350);
DISPLAY INVISIBLE (3950 -350);
FORCEPROP 2 LAST SEC_TYPE DISCRET-GB2
J 0
(3825 -275);
DISPLAY 1.021277 (3825 -275);
PAINT ORANGE (3825 -275);
DISPLAY INVISIBLE (3825 -275);
FORCEPROP 2 LAST SEC 1
J 0
(3825 -275);
DISPLAY 0.680851 (3825 -275);
PAINT MONO (3825 -275);
DISPLAY INVISIBLE (3825 -275);
FORCEPROP 1 LAST PACK_TYPE DISCRET-GB2
R 1
J 0
(3950 -350);
DISPLAY 0.617021 (3950 -350);
PAINT GREEN (3950 -350);
DISPLAY INVISIBLE (3950 -350);
FORCEPROP 1 LAST VALUE IND-120NH-30-GP
J 0
(3800 -450);
DISPLAY 0.617021 (3800 -450);
PAINT GREEN (3800 -450);
DISPLAY INVISIBLE (3800 -450);
FORCEPROP 0 LAST ATTRIBUTE 120NH
J 0
(3800 -500);
DISPLAY 0.638298 (3800 -500);
PAINT GREEN (3800 -500);
DISPLAY INVISIBLE (3800 -500);
FORCEPROP 0 LAST RATED ISAT=94A@25C
J 0
(3800 -550);
DISPLAY 0.638298 (3800 -550);
PAINT GREEN (3800 -550);
DISPLAY INVISIBLE (3800 -550);
FORCEPROP 0 LAST PACK_SIZE DCR=0.17MOHM
J 0
(3800 -650);
DISPLAY 0.638298 (3800 -650);
PAINT GREEN (3800 -650);
DISPLAY INVISIBLE (3800 -650);
FORCEPROP 0 LAST TYPE IRMS=66A@DELTA_T<40C
J 0
(3800 -600);
DISPLAY 0.638298 (3800 -600);
PAINT GREEN (3800 -600);
DISPLAY INVISIBLE (3800 -600);
FORCEPROP 1 LAST PATH I155
R 1
J 0
(3950 -350);
DISPLAY 0.617021 (3950 -350);
PAINT GREEN (3950 -350);
DISPLAY INVISIBLE (3950 -350);
FORCEADD GND..1
(2450 1625);
FORCEPROP 3 LASTPIN (2450 1675) SIG_NAME GND\g
J 0
(2460 1685);
DISPLAY 0.659574 (2460 1685);
PAINT MONO (2460 1685);
DISPLAY INVISIBLE (2460 1685);
FORCEPROP 1 LAST HDL_POWER GND
J 0
(2450 1775);
DISPLAY 1.723404 (2450 1775);
PAINT GREEN (2450 1775);
DISPLAY INVISIBLE (2450 1775);
FORCEPROP 1 LAST BODY_TYPE PLUMBING
J 0
(2405 1582);
DISPLAY 0.340426 (2405 1582);
PAINT GREEN (2405 1582);
DISPLAY INVISIBLE (2405 1582);
FORCEPROP 2 LAST ROOM VDDQ_ABC_PWR_VR
J 0
(1900 1700);
DISPLAY 1.936170 (1900 1700);
PAINT ORANGE (1900 1700);
DISPLAY INVISIBLE (1900 1700);
FORCEPROP 2 LAST BOM_COST PROC_VRD_VCCIN_CPU0
J 0
(2075 1700);
DISPLAY 1.446809 (2075 1700);
PAINT MONO (2075 1700);
DISPLAY INVISIBLE (2075 1700);
FORCEPROP 1 LAST SIZE 1B
J 0
(2525 1575);
DISPLAY 1.723404 (2525 1575);
PAINT GREEN (2525 1575);
DISPLAY INVISIBLE (2525 1575);
FORCEPROP 1 LAST PATH I19
J 0
(2525 1625);
DISPLAY 0.893617 (2525 1625);
PAINT AQUA (2525 1625);
DISPLAY INVISIBLE (2525 1625);
FORCEPROP 2 LAST CDS_LIB mstr_symbols
J 0
(2450 1625);
DISPLAY 1.936170 (2450 1625);
PAINT ORANGE (2450 1625);
DISPLAY INVISIBLE (2450 1625);
FORCEPROP 1 LAST VOLTAGE 0
J 0
(2450 1625);
PAINT SKYBLUE (2450 1625);
DISPLAY INVISIBLE (2450 1625);
FORCEADD OFFPAGE..2
(3625 2850);
FORCEPROP 2 LAST $XR0 215 
J 0
(3814 2850);
DISPLAY 0.638298 (3814 2850);
PAINT MONO (3814 2850);
FORCEPROP 1 LAST COMMENT_BODY TRUE
J 0
(3580 2755);
DISPLAY 1.723404 (3580 2755);
PAINT GREEN (3580 2755);
DISPLAY INVISIBLE (3580 2755);
FORCEPROP 1 LAST OFFPAGE TRUE
J 0
(3950 2725);
DISPLAY 1.723404 (3950 2725);
PAINT GREEN (3950 2725);
DISPLAY INVISIBLE (3950 2725);
FORCEPROP 2 LAST ROOM VDDQ_ABC_PWR_VR
J 0
(3225 2925);
DISPLAY 1.936170 (3225 2925);
PAINT ORANGE (3225 2925);
DISPLAY INVISIBLE (3225 2925);
FORCEPROP 2 LAST CDS_LIB mstr_standard
J 0
(3625 2850);
DISPLAY 1.936170 (3625 2850);
PAINT ORANGE (3625 2850);
DISPLAY INVISIBLE (3625 2850);
FORCEPROP 2 LAST PATH I3
J 0
(3815 2900);
DISPLAY 1.021277 (3815 2900);
PAINT ORANGE (3815 2900);
DISPLAY INVISIBLE (3815 2900);
FORCEPROP 2 LAST BOM_COST PROC_VRD_VCCIN_CPU0
J 0
(3825 2900);
DISPLAY 1.446809 (3825 2900);
PAINT MONO (3825 2900);
DISPLAY INVISIBLE (3825 2900);
FORCEADD OFFPAGE..1
(-1525 2200);
FORCEPROP 2 LASTPIN (-1475 2200) SIG_NAME VR_PVDDQ_ABC_PWM1
J 0
(-1460 2210);
DISPLAY 0.617021 (-1460 2210);
PAINT ORANGE (-1460 2210);
FORCEPROP 2 LAST $XR0 215 
J 0
(-1777 2200);
DISPLAY 0.638298 (-1777 2200);
PAINT MONO (-1777 2200);
FORCEPROP 1 LAST COMMENT_BODY TRUE
J 0
(-1400 2100);
DISPLAY 1.680851 (-1400 2100);
PAINT GREEN (-1400 2100);
DISPLAY INVISIBLE (-1400 2100);
FORCEPROP 1 LAST OFFPAGE TRUE
J 0
(-1200 2075);
DISPLAY 1.680851 (-1200 2075);
PAINT GREEN (-1200 2075);
DISPLAY INVISIBLE (-1200 2075);
FORCEPROP 2 LAST BOM_COST PROC_VRD_VCCIN_CPU0
J 0
(-1775 2250);
DISPLAY 1.446809 (-1775 2250);
PAINT MONO (-1775 2250);
DISPLAY INVISIBLE (-1775 2250);
FORCEPROP 2 LAST PATH I33
J 0
(-1805 2250);
DISPLAY 1.021277 (-1805 2250);
PAINT ORANGE (-1805 2250);
DISPLAY INVISIBLE (-1805 2250);
FORCEPROP 2 LAST ROOM VDDQ_ABC_PWR_VR
J 0
(-1925 2275);
DISPLAY 1.936170 (-1925 2275);
PAINT ORANGE (-1925 2275);
DISPLAY INVISIBLE (-1925 2275);
FORCEPROP 2 LAST CDS_LIB mstr_standard
J 0
(-1525 2200);
DISPLAY 1.936170 (-1525 2200);
PAINT ORANGE (-1525 2200);
DISPLAY INVISIBLE (-1525 2200);
FORCEADD GND..1
(-2050 2050);
FORCEPROP 3 LASTPIN (-2050 2100) SIG_NAME GND\g
J 0
(-2040 2110);
DISPLAY 0.659574 (-2040 2110);
PAINT MONO (-2040 2110);
DISPLAY INVISIBLE (-2040 2110);
FORCEPROP 1 LAST HDL_POWER GND
J 0
(-2050 2200);
DISPLAY 1.723404 (-2050 2200);
PAINT GREEN (-2050 2200);
DISPLAY INVISIBLE (-2050 2200);
FORCEPROP 1 LAST BODY_TYPE PLUMBING
J 0
(-2095 2007);
DISPLAY 0.340426 (-2095 2007);
PAINT GREEN (-2095 2007);
DISPLAY INVISIBLE (-2095 2007);
FORCEPROP 2 LAST CDS_LIB mstr_symbols
J 0
(-2050 2050);
DISPLAY 1.936170 (-2050 2050);
PAINT ORANGE (-2050 2050);
DISPLAY INVISIBLE (-2050 2050);
FORCEPROP 1 LAST VOLTAGE 0
J 0
(-2050 2050);
PAINT SKYBLUE (-2050 2050);
DISPLAY INVISIBLE (-2050 2050);
FORCEPROP 1 LAST PATH I35
J 0
(-1975 2050);
DISPLAY 0.893617 (-1975 2050);
PAINT AQUA (-1975 2050);
DISPLAY INVISIBLE (-1975 2050);
FORCEPROP 2 LAST BOM_COST PROC_VRD_VCCIN_CPU0
J 0
(-2425 2125);
DISPLAY 1.446809 (-2425 2125);
PAINT MONO (-2425 2125);
DISPLAY INVISIBLE (-2425 2125);
FORCEPROP 2 LAST ROOM VDDQ_ABC_PWR_VR
J 0
(-2600 2125);
DISPLAY 1.936170 (-2600 2125);
PAINT ORANGE (-2600 2125);
DISPLAY INVISIBLE (-2600 2125);
FORCEPROP 1 LAST SIZE 1B
J 0
(-1975 2000);
DISPLAY 1.723404 (-1975 2000);
PAINT GREEN (-1975 2000);
DISPLAY INVISIBLE (-1975 2000);
FORCEADD OFFPAGE..2
(3600 3175);
FORCEPROP 2 LAST $XR0 215 
J 0
(3789 3175);
DISPLAY 0.638298 (3789 3175);
PAINT MONO (3789 3175);
FORCEPROP 1 LAST COMMENT_BODY TRUE
J 0
(3555 3080);
DISPLAY 1.723404 (3555 3080);
PAINT GREEN (3555 3080);
DISPLAY INVISIBLE (3555 3080);
FORCEPROP 1 LAST OFFPAGE TRUE
J 0
(3925 3050);
DISPLAY 1.723404 (3925 3050);
PAINT GREEN (3925 3050);
DISPLAY INVISIBLE (3925 3050);
FORCEPROP 2 LAST ROOM VDDQ_ABC_PWR_VR
J 0
(3200 3250);
DISPLAY 1.936170 (3200 3250);
PAINT ORANGE (3200 3250);
DISPLAY INVISIBLE (3200 3250);
FORCEPROP 2 LAST CDS_LIB mstr_standard
J 2
(3600 3175);
DISPLAY 1.936170 (3600 3175);
PAINT ORANGE (3600 3175);
DISPLAY INVISIBLE (3600 3175);
FORCEPROP 2 LAST PATH I4
J 0
(3790 3225);
DISPLAY 1.021277 (3790 3225);
PAINT ORANGE (3790 3225);
DISPLAY INVISIBLE (3790 3225);
FORCEPROP 2 LAST BOM_COST PROC_VRD_VCCIN_CPU0
J 0
(3800 3225);
DISPLAY 1.446809 (3800 3225);
PAINT MONO (3800 3225);
DISPLAY INVISIBLE (3800 3225);
FORCEADD CAP..1
R 2
(-675 1925);
FORCEPROP 1 LAST TOLERANCE 10%
J 2
(-725 1875);
DISPLAY 0.617021 (-725 1875);
PAINT SKYBLUE (-725 1875);
FORCEPROP 1 LAST VOLTAGE 16V
J 2
(-725 1925);
DISPLAY 0.617021 (-725 1925);
PAINT SKYBLUE (-725 1925);
FORCEPROP 1 LAST MATERIAL X7R
J 2
(-725 1825);
DISPLAY 0.617021 (-725 1825);
PAINT SKYBLUE (-725 1825);
FORCEPROP 1 LAST VALUE 0.220UF
J 2
(-725 1975);
DISPLAY 0.617021 (-725 1975);
PAINT SKYBLUE (-725 1975);
FORCEPROP 1 LAST PACK_TYPE 0402
J 2
(-725 1725);
DISPLAY 0.617021 (-725 1725);
PAINT SKYBLUE (-725 1725);
FORCEPROP 1 LAST PART_NUMBER A36096-104
J 2
(-725 1775);
DISPLAY 0.617021 (-725 1775);
PAINT BLUE (-725 1775);
FORCEPROP 1 LASTPIN (-675 1825) $PN 2
J 2
(-685 1805);
DISPLAY 0.617021 (-685 1805);
PAINT ORANGE (-685 1805);
FORCEPROP 1 LASTPIN (-675 2025) $PN 1
J 2
(-685 2005);
DISPLAY 0.617021 (-685 2005);
PAINT ORANGE (-685 2005);
FORCEPROP 1 LAST LOCATION C7G31
J 2
(-725 2025);
DISPLAY 0.617021 (-725 2025);
PAINT AQUA (-725 2025);
FORCEPROP 2 LAST CDS_LIB mstr_discrete
J 0
(-675 1925);
PAINT ORANGE (-675 1925);
DISPLAY INVISIBLE (-675 1925);
FORCEPROP 2 LAST SEC_TYPE 0402
J 0
(-725 2125);
DISPLAY 1.021277 (-725 2125);
PAINT ORANGE (-725 2125);
DISPLAY INVISIBLE (-725 2125);
FORCEPROP 0 LAST SPOF TRUE
J 0
(-725 2125);
DISPLAY 1.021277 (-725 2125);
PAINT ORANGE (-725 2125);
DISPLAY INVISIBLE (-725 2125);
FORCEPROP 2 LAST SEC 1
J 0
(-725 2125);
DISPLAY 0.680851 (-725 2125);
PAINT MONO (-725 2125);
DISPLAY INVISIBLE (-725 2125);
FORCEPROP 2 LAST CDS_LOCATION C7G31
J 2
(-725 2025);
DISPLAY 0.617021 (-725 2025);
PAINT AQUA (-725 2025);
DISPLAY INVISIBLE (-725 2025);
FORCEPROP 1 LAST PATH I44
J 2
(-725 2075);
DISPLAY 0.978723 (-725 2075);
PAINT WHITE (-725 2075);
DISPLAY INVISIBLE (-725 2075);
FORCEPROP 2 LAST ROOM VDDQ_ABC_PWR_VR
J 0
(-750 2075);
DISPLAY 1.361702 (-750 2075);
PAINT ORANGE (-750 2075);
DISPLAY INVISIBLE (-750 2075);
FORCEADD CAP..1
(-2050 2525);
FORCEPROP 1 LASTPIN (-2050 2425) $PN 2
J 0
(-2040 2405);
DISPLAY 0.617021 (-2040 2405);
PAINT ORANGE (-2040 2405);
FORCEPROP 1 LAST PACK_TYPE 0805
J 0
(-2000 2325);
DISPLAY 0.617021 (-2000 2325);
PAINT SKYBLUE (-2000 2325);
FORCEPROP 1 LAST MATERIAL X6S
J 0
(-2000 2425);
DISPLAY 0.617021 (-2000 2425);
PAINT SKYBLUE (-2000 2425);
FORCEPROP 1 LAST VOLTAGE 16V
J 0
(-2000 2525);
DISPLAY 0.617021 (-2000 2525);
PAINT SKYBLUE (-2000 2525);
FORCEPROP 1 LAST TOLERANCE 10%
J 0
(-2000 2475);
DISPLAY 0.617021 (-2000 2475);
PAINT SKYBLUE (-2000 2475);
FORCEPROP 1 LAST PART_NUMBER C95333-007
J 0
(-2000 2375);
DISPLAY 0.617021 (-2000 2375);
PAINT BLUE (-2000 2375);
FORCEPROP 1 LASTPIN (-2050 2625) $PN 1
J 0
(-2040 2605);
DISPLAY 0.617021 (-2040 2605);
PAINT ORANGE (-2040 2605);
FORCEPROP 1 LAST LOCATION C3U2
J 0
(-2000 2625);
DISPLAY 0.617021 (-2000 2625);
PAINT AQUA (-2000 2625);
FORCEPROP 1 LAST VALUE 10UF
J 0
(-2000 2575);
DISPLAY 0.617021 (-2000 2575);
PAINT SKYBLUE (-2000 2575);
FORCEPROP 2 LAST SEC_TYPE 0805
J 0
(-2000 2750);
DISPLAY 1.021277 (-2000 2750);
PAINT ORANGE (-2000 2750);
DISPLAY INVISIBLE (-2000 2750);
FORCEPROP 2 LAST SEC 1
J 0
(-2000 2750);
DISPLAY 0.680851 (-2000 2750);
PAINT MONO (-2000 2750);
DISPLAY INVISIBLE (-2000 2750);
FORCEPROP 1 LAST PATH I45
J 0
(-2000 2675);
DISPLAY 1.319149 (-2000 2675);
PAINT WHITE (-2000 2675);
DISPLAY INVISIBLE (-2000 2675);
FORCEPROP 2 LAST ROOM VDDQ_ABC_PWR_VR
J 0
(-2000 2675);
DISPLAY 1.361702 (-2000 2675);
PAINT ORANGE (-2000 2675);
DISPLAY INVISIBLE (-2000 2675);
FORCEPROP 2 LAST CDS_LOCATION C3U2
J 0
(-2000 2625);
DISPLAY 0.617021 (-2000 2625);
PAINT AQUA (-2000 2625);
DISPLAY INVISIBLE (-2000 2625);
FORCEPROP 2 LAST CDS_LIB mstr_discrete
J 0
(-2050 2525);
PAINT ORANGE (-2050 2525);
DISPLAY INVISIBLE (-2050 2525);
FORCEADD CAP..1
(-1775 2525);
FORCEPROP 1 LAST PACK_TYPE 0805
J 0
(-1725 2300);
DISPLAY 0.617021 (-1725 2300);
PAINT SKYBLUE (-1725 2300);
FORCEPROP 1 LAST MATERIAL X6S
J 0
(-1725 2425);
DISPLAY 0.617021 (-1725 2425);
PAINT SKYBLUE (-1725 2425);
FORCEPROP 1 LASTPIN (-1775 2425) $PN 2
J 0
(-1765 2430);
DISPLAY 0.617021 (-1765 2430);
PAINT ORANGE (-1765 2430);
FORCEPROP 1 LAST TOLERANCE 10%
J 0
(-1725 2475);
DISPLAY 0.617021 (-1725 2475);
PAINT SKYBLUE (-1725 2475);
FORCEPROP 1 LAST VOLTAGE 16V
J 0
(-1725 2525);
DISPLAY 0.617021 (-1725 2525);
PAINT SKYBLUE (-1725 2525);
FORCEPROP 1 LASTPIN (-1775 2625) $PN 1
J 0
(-1765 2605);
DISPLAY 0.617021 (-1765 2605);
PAINT ORANGE (-1765 2605);
FORCEPROP 1 LAST VALUE 10UF
J 0
(-1725 2575);
DISPLAY 0.617021 (-1725 2575);
PAINT SKYBLUE (-1725 2575);
FORCEPROP 1 LAST LOCATION C3U3
J 0
(-1725 2625);
DISPLAY 0.617021 (-1725 2625);
PAINT AQUA (-1725 2625);
FORCEPROP 1 LAST PART_NUMBER C95333-007
J 0
(-1750 2375);
DISPLAY 0.617021 (-1750 2375);
PAINT BLUE (-1750 2375);
FORCEPROP 2 LAST CDS_LOCATION C3U3
J 0
(-1725 2625);
DISPLAY 0.617021 (-1725 2625);
PAINT AQUA (-1725 2625);
DISPLAY INVISIBLE (-1725 2625);
FORCEPROP 2 LAST SEC 1
J 0
(-1725 2750);
DISPLAY 0.680851 (-1725 2750);
PAINT MONO (-1725 2750);
DISPLAY INVISIBLE (-1725 2750);
FORCEPROP 2 LAST SEC_TYPE 0805
J 0
(-1725 2750);
DISPLAY 1.021277 (-1725 2750);
PAINT ORANGE (-1725 2750);
DISPLAY INVISIBLE (-1725 2750);
FORCEPROP 2 LAST ROOM VDDQ_ABC_PWR_VR
J 0
(-1725 2675);
DISPLAY 1.361702 (-1725 2675);
PAINT ORANGE (-1725 2675);
DISPLAY INVISIBLE (-1725 2675);
FORCEPROP 1 LAST PATH I46
J 0
(-1725 2675);
DISPLAY 1.319149 (-1725 2675);
PAINT WHITE (-1725 2675);
DISPLAY INVISIBLE (-1725 2675);
FORCEPROP 2 LAST CDS_LIB mstr_discrete
J 0
(-1775 2525);
PAINT ORANGE (-1775 2525);
DISPLAY INVISIBLE (-1775 2525);
FORCEADD CAP..1
(-1525 2525);
FORCEPROP 1 LAST PACK_TYPE 0805
J 0
(-1500 2300);
DISPLAY 0.617021 (-1500 2300);
PAINT SKYBLUE (-1500 2300);
FORCEPROP 1 LAST VOLTAGE 16V
J 0
(-1475 2525);
DISPLAY 0.617021 (-1475 2525);
PAINT SKYBLUE (-1475 2525);
FORCEPROP 1 LASTPIN (-1525 2425) $PN 2
J 0
(-1515 2405);
DISPLAY 0.617021 (-1515 2405);
PAINT ORANGE (-1515 2405);
FORCEPROP 1 LAST MATERIAL X6S
J 0
(-1475 2425);
DISPLAY 0.617021 (-1475 2425);
PAINT SKYBLUE (-1475 2425);
FORCEPROP 1 LAST TOLERANCE 10%
J 0
(-1475 2475);
DISPLAY 0.617021 (-1475 2475);
PAINT SKYBLUE (-1475 2475);
FORCEPROP 1 LAST PART_NUMBER C95333-007
J 0
(-1500 2350);
DISPLAY 0.617021 (-1500 2350);
PAINT BLUE (-1500 2350);
FORCEPROP 1 LASTPIN (-1525 2625) $PN 1
J 0
(-1515 2605);
DISPLAY 0.617021 (-1515 2605);
PAINT ORANGE (-1515 2605);
FORCEPROP 1 LAST LOCATION C3U4
J 0
(-1475 2625);
DISPLAY 0.617021 (-1475 2625);
PAINT AQUA (-1475 2625);
FORCEPROP 1 LAST VALUE 10UF
J 0
(-1475 2575);
DISPLAY 0.617021 (-1475 2575);
PAINT SKYBLUE (-1475 2575);
FORCEPROP 2 LAST SEC_TYPE 0805
J 0
(-1475 2750);
DISPLAY 1.021277 (-1475 2750);
PAINT ORANGE (-1475 2750);
DISPLAY INVISIBLE (-1475 2750);
FORCEPROP 2 LAST ROOM VDDQ_ABC_PWR_VR
J 0
(-1475 2675);
DISPLAY 1.361702 (-1475 2675);
PAINT ORANGE (-1475 2675);
DISPLAY INVISIBLE (-1475 2675);
FORCEPROP 1 LAST PATH I47
J 0
(-1475 2675);
DISPLAY 1.319149 (-1475 2675);
PAINT WHITE (-1475 2675);
DISPLAY INVISIBLE (-1475 2675);
FORCEPROP 2 LAST CDS_LOCATION C3U4
J 0
(-1475 2625);
DISPLAY 0.617021 (-1475 2625);
PAINT AQUA (-1475 2625);
DISPLAY INVISIBLE (-1475 2625);
FORCEPROP 2 LAST SEC 1
J 0
(-1475 2750);
DISPLAY 0.680851 (-1475 2750);
PAINT MONO (-1475 2750);
DISPLAY INVISIBLE (-1475 2750);
FORCEPROP 2 LAST CDS_LIB mstr_discrete
J 0
(-1525 2525);
PAINT ORANGE (-1525 2525);
DISPLAY INVISIBLE (-1525 2525);
FORCEADD CAP..1
(-1275 2525);
FORCEPROP 1 LAST VOLTAGE 16V
J 0
(-1225 2525);
DISPLAY 0.617021 (-1225 2525);
PAINT SKYBLUE (-1225 2525);
FORCEPROP 1 LASTPIN (-1275 2425) $PN 2
J 0
(-1265 2405);
DISPLAY 0.617021 (-1265 2405);
PAINT ORANGE (-1265 2405);
FORCEPROP 1 LAST MATERIAL X6S
J 0
(-1225 2425);
DISPLAY 0.617021 (-1225 2425);
PAINT SKYBLUE (-1225 2425);
FORCEPROP 1 LAST TOLERANCE 10%
J 0
(-1225 2475);
DISPLAY 0.617021 (-1225 2475);
PAINT SKYBLUE (-1225 2475);
FORCEPROP 1 LAST PACK_TYPE 0402
J 0
(-1225 2325);
DISPLAY 0.617021 (-1225 2325);
PAINT SKYBLUE (-1225 2325);
FORCEPROP 1 LASTPIN (-1275 2625) $PN 1
J 0
(-1265 2605);
DISPLAY 0.617021 (-1265 2605);
PAINT ORANGE (-1265 2605);
FORCEPROP 1 LAST VALUE 1.0UF
J 0
(-1225 2575);
DISPLAY 0.617021 (-1225 2575);
PAINT SKYBLUE (-1225 2575);
FORCEPROP 1 LAST LOCATION C7G37
J 0
(-1225 2625);
DISPLAY 0.617021 (-1225 2625);
PAINT AQUA (-1225 2625);
FORCEPROP 1 LAST PART_NUMBER D97712-011
J 0
(-1225 2375);
DISPLAY 0.617021 (-1225 2375);
PAINT BLUE (-1225 2375);
FORCEPROP 2 LAST CDS_LIB mstr_discrete
J 0
(-1275 2525);
PAINT ORANGE (-1275 2525);
DISPLAY INVISIBLE (-1275 2525);
FORCEPROP 2 LAST SEC_TYPE 0402
J 0
(-1225 2750);
DISPLAY 1.021277 (-1225 2750);
PAINT ORANGE (-1225 2750);
DISPLAY INVISIBLE (-1225 2750);
FORCEPROP 2 LAST SEC 1
J 0
(-1225 2750);
DISPLAY 0.680851 (-1225 2750);
PAINT MONO (-1225 2750);
DISPLAY INVISIBLE (-1225 2750);
FORCEPROP 2 LAST CDS_LOCATION C7G37
J 0
(-1225 2625);
DISPLAY 0.617021 (-1225 2625);
PAINT AQUA (-1225 2625);
DISPLAY INVISIBLE (-1225 2625);
FORCEPROP 1 LAST PATH I48
J 0
(-1225 2675);
DISPLAY 1.319149 (-1225 2675);
PAINT WHITE (-1225 2675);
DISPLAY INVISIBLE (-1225 2675);
FORCEPROP 2 LAST ROOM VDDQ_ABC_PWR_VR
J 0
(-1225 2675);
DISPLAY 1.361702 (-1225 2675);
PAINT ORANGE (-1225 2675);
DISPLAY INVISIBLE (-1225 2675);
FORCEADD CAP..1
(-725 2525);
FORCEPROP 1 LAST TOLERANCE 10%
J 0
(-675 2475);
DISPLAY 0.617021 (-675 2475);
PAINT SKYBLUE (-675 2475);
FORCEPROP 1 LASTPIN (-725 2425) $PN 2
J 0
(-715 2405);
DISPLAY 0.617021 (-715 2405);
PAINT ORANGE (-715 2405);
FORCEPROP 1 LAST MATERIAL X6S
J 0
(-675 2425);
DISPLAY 0.617021 (-675 2425);
PAINT SKYBLUE (-675 2425);
FORCEPROP 1 LAST VOLTAGE 16V
J 0
(-675 2525);
DISPLAY 0.617021 (-675 2525);
PAINT SKYBLUE (-675 2525);
FORCEPROP 1 LAST PACK_TYPE 0402
J 0
(-675 2325);
DISPLAY 0.617021 (-675 2325);
PAINT SKYBLUE (-675 2325);
FORCEPROP 1 LASTPIN (-725 2625) $PN 1
J 0
(-715 2605);
DISPLAY 0.617021 (-715 2605);
PAINT ORANGE (-715 2605);
FORCEPROP 1 LAST VALUE 1.0UF
J 0
(-675 2575);
DISPLAY 0.617021 (-675 2575);
PAINT SKYBLUE (-675 2575);
FORCEPROP 1 LAST LOCATION C7G33
J 0
(-675 2625);
DISPLAY 0.617021 (-675 2625);
PAINT AQUA (-675 2625);
FORCEPROP 1 LAST PART_NUMBER D97712-011
J 0
(-675 2375);
DISPLAY 0.617021 (-675 2375);
PAINT BLUE (-675 2375);
FORCEPROP 2 LAST ROOM VDDQ_ABC_PWR_VR
J 0
(-675 2675);
DISPLAY 1.361702 (-675 2675);
PAINT ORANGE (-675 2675);
DISPLAY INVISIBLE (-675 2675);
FORCEPROP 1 LAST PATH I50
J 0
(-675 2675);
DISPLAY 1.319149 (-675 2675);
PAINT WHITE (-675 2675);
DISPLAY INVISIBLE (-675 2675);
FORCEPROP 2 LAST CDS_LOCATION C7G33
J 0
(-675 2625);
DISPLAY 0.617021 (-675 2625);
PAINT AQUA (-675 2625);
DISPLAY INVISIBLE (-675 2625);
FORCEPROP 2 LAST SEC 1
J 0
(-675 2750);
DISPLAY 0.680851 (-675 2750);
PAINT MONO (-675 2750);
DISPLAY INVISIBLE (-675 2750);
FORCEPROP 2 LAST SEC_TYPE 0402
J 0
(-675 2750);
DISPLAY 1.021277 (-675 2750);
PAINT ORANGE (-675 2750);
DISPLAY INVISIBLE (-675 2750);
FORCEPROP 2 LAST CDS_LIB mstr_discrete
J 0
(-725 2525);
PAINT ORANGE (-725 2525);
DISPLAY INVISIBLE (-725 2525);
FORCEADD CAP_A..1
(-1000 2525);
FORCEPROP 1 LAST PACK_TYPE 0402V
J 0
(-950 2325);
DISPLAY 0.617021 (-950 2325);
PAINT SKYBLUE (-950 2325);
FORCEPROP 1 LAST VOLTAGE 16V
J 0
(-950 2525);
DISPLAY 0.617021 (-950 2525);
PAINT SKYBLUE (-950 2525);
FORCEPROP 1 LAST TOLERANCE 10%
J 0
(-950 2475);
DISPLAY 0.617021 (-950 2475);
PAINT SKYBLUE (-950 2475);
FORCEPROP 1 LASTPIN (-1000 2425) $PN 2
J 0
(-990 2405);
DISPLAY 0.617021 (-990 2405);
PAINT ORANGE (-990 2405);
FORCEPROP 1 LAST MATERIAL X7R
J 0
(-950 2425);
DISPLAY 0.617021 (-950 2425);
PAINT SKYBLUE (-950 2425);
FORCEPROP 1 LAST PART_NUMBER A36096-030
J 0
(-950 2375);
DISPLAY 0.617021 (-950 2375);
PAINT BLUE (-950 2375);
FORCEPROP 1 LASTPIN (-1000 2625) $PN 1
J 0
(-990 2605);
DISPLAY 0.617021 (-990 2605);
PAINT ORANGE (-990 2605);
FORCEPROP 1 LAST VALUE 0.1UF
J 0
(-950 2575);
DISPLAY 0.617021 (-950 2575);
PAINT SKYBLUE (-950 2575);
FORCEPROP 1 LAST LOCATION C7G29
J 0
(-950 2625);
DISPLAY 0.617021 (-950 2625);
PAINT AQUA (-950 2625);
FORCEPROP 2 LAST CDS_LIB dev_discrete
J 0
(-1000 2525);
PAINT ORANGE (-1000 2525);
DISPLAY INVISIBLE (-1000 2525);
FORCEPROP 2 LAST SEC 1
J 0
(-950 2750);
DISPLAY 0.680851 (-950 2750);
PAINT MONO (-950 2750);
DISPLAY INVISIBLE (-950 2750);
FORCEPROP 2 LAST SEC_TYPE 0402V
J 0
(-950 2750);
DISPLAY 1.021277 (-950 2750);
PAINT ORANGE (-950 2750);
DISPLAY INVISIBLE (-950 2750);
FORCEPROP 2 LAST CDS_SEC 1
J 0
(-950 2675);
PAINT ORANGE (-950 2675);
DISPLAY INVISIBLE (-950 2675);
FORCEPROP 2 LAST CDS_LOCATION C7G29
J 0
(-950 2625);
DISPLAY 0.617021 (-950 2625);
PAINT AQUA (-950 2625);
DISPLAY INVISIBLE (-950 2625);
FORCEPROP 2 LAST ROOM VDDQ_ABC_PWR_VR
J 0
(-950 2675);
DISPLAY 1.361702 (-950 2675);
PAINT ORANGE (-950 2675);
DISPLAY INVISIBLE (-950 2675);
FORCEPROP 1 LAST PATH I51
J 0
(-950 2675);
DISPLAY 0.978723 (-950 2675);
PAINT WHITE (-950 2675);
DISPLAY INVISIBLE (-950 2675);
FORCEADD CAP..1
(100 2550);
FORCEPROP 1 LASTPIN (100 2450) $PN 2
J 0
(110 2430);
DISPLAY 0.617021 (110 2430);
PAINT ORANGE (110 2430);
FORCEPROP 1 LAST MATERIAL X7R
J 0
(150 2450);
DISPLAY 0.617021 (150 2450);
PAINT SKYBLUE (150 2450);
FORCEPROP 1 LAST TOLERANCE 10%
J 0
(150 2500);
DISPLAY 0.617021 (150 2500);
PAINT SKYBLUE (150 2500);
FORCEPROP 1 LAST PART_NUMBER A36096-155
J 0
(150 2400);
DISPLAY 0.617021 (150 2400);
PAINT BLUE (150 2400);
FORCEPROP 1 LAST PACK_TYPE 0402
J 0
(150 2350);
DISPLAY 0.617021 (150 2350);
PAINT SKYBLUE (150 2350);
FORCEPROP 1 LAST VOLTAGE 16V
J 0
(150 2550);
DISPLAY 0.617021 (150 2550);
PAINT SKYBLUE (150 2550);
FORCEPROP 1 LASTPIN (100 2650) $PN 1
J 0
(110 2630);
DISPLAY 0.617021 (110 2630);
PAINT ORANGE (110 2630);
FORCEPROP 1 LAST LOCATION C7G34
J 0
(150 2650);
DISPLAY 0.617021 (150 2650);
PAINT AQUA (150 2650);
FORCEPROP 1 LAST VALUE 0.22UF
J 0
(150 2600);
DISPLAY 0.617021 (150 2600);
PAINT SKYBLUE (150 2600);
FORCEPROP 2 LAST ROOM VDDQ_ABC_PWR_VR
J 0
(150 2700);
DISPLAY 1.361702 (150 2700);
PAINT ORANGE (150 2700);
DISPLAY INVISIBLE (150 2700);
FORCEPROP 1 LAST PATH I54
J 0
(150 2700);
DISPLAY 1.319149 (150 2700);
PAINT WHITE (150 2700);
DISPLAY INVISIBLE (150 2700);
FORCEPROP 2 LAST CDS_LOCATION C7G34
J 0
(150 2650);
DISPLAY 0.617021 (150 2650);
PAINT AQUA (150 2650);
DISPLAY INVISIBLE (150 2650);
FORCEPROP 2 LAST SEC 1
J 0
(150 2775);
DISPLAY 0.680851 (150 2775);
PAINT MONO (150 2775);
DISPLAY INVISIBLE (150 2775);
FORCEPROP 2 LAST SEC_TYPE 0402
J 0
(150 2775);
DISPLAY 1.021277 (150 2775);
PAINT ORANGE (150 2775);
DISPLAY INVISIBLE (150 2775);
FORCEPROP 2 LAST CDS_LIB mstr_discrete
J 0
(100 2550);
PAINT ORANGE (100 2550);
DISPLAY INVISIBLE (100 2550);
FORCEADD OFFPAGE..2
(3625 2500);
FORCEPROP 2 LAST $XR1 215 
J 0
(3934 2500);
DISPLAY 0.638298 (3934 2500);
PAINT MONO (3934 2500);
FORCEPROP 2 LAST $XR0 216 
J 0
(3814 2500);
DISPLAY 0.638298 (3814 2500);
PAINT MONO (3814 2500);
FORCEPROP 1 LAST COMMENT_BODY TRUE
J 0
(3580 2405);
DISPLAY 1.723404 (3580 2405);
PAINT GREEN (3580 2405);
DISPLAY INVISIBLE (3580 2405);
FORCEPROP 1 LAST OFFPAGE TRUE
J 0
(3950 2375);
DISPLAY 1.723404 (3950 2375);
PAINT GREEN (3950 2375);
DISPLAY INVISIBLE (3950 2375);
FORCEPROP 2 LAST BOM_COST PROC_VRD_VCCIN_CPU0
J 0
(3825 2550);
DISPLAY 1.446809 (3825 2550);
PAINT MONO (3825 2550);
DISPLAY INVISIBLE (3825 2550);
FORCEPROP 2 LAST PATH I58
J 0
(3805 2575);
DISPLAY 1.361702 (3805 2575);
PAINT ORANGE (3805 2575);
DISPLAY INVISIBLE (3805 2575);
FORCEPROP 2 LAST CDS_LIB mstr_standard
J 0
(3625 2500);
PAINT ORANGE (3625 2500);
DISPLAY INVISIBLE (3625 2500);
FORCEPROP 2 LAST ROOM VDDQ_ABC_PWR_VR
J 0
(3225 2575);
DISPLAY 1.936170 (3225 2575);
PAINT ORANGE (3225 2575);
DISPLAY INVISIBLE (3225 2575);
FORCEADD CAP..1
(4350 1850);
FORCEPROP 1 LASTPIN (4350 1750) $PN 2
J 0
(4360 1730);
DISPLAY 0.617021 (4360 1730);
PAINT GREEN (4360 1730);
FORCEPROP 1 LAST MATERIAL X6S
J 0
(4400 1750);
DISPLAY 0.617021 (4400 1750);
PAINT SKYBLUE (4400 1750);
FORCEPROP 1 LAST TOLERANCE 20%
J 0
(4400 1800);
DISPLAY 0.617021 (4400 1800);
PAINT SKYBLUE (4400 1800);
FORCEPROP 1 LAST VALUE 22UF
J 0
(4400 1900);
DISPLAY 0.617021 (4400 1900);
PAINT SKYBLUE (4400 1900);
FORCEPROP 1 LASTPIN (4350 1950) $PN 1
J 0
(4360 1930);
DISPLAY 0.617021 (4360 1930);
PAINT GREEN (4360 1930);
FORCEPROP 1 LAST LOCATION C6G3
J 0
(4400 1950);
DISPLAY 0.617021 (4400 1950);
PAINT AQUA (4400 1950);
FORCEPROP 1 LAST PACK_TYPE 0805LF
J 0
(4400 1650);
DISPLAY 0.617021 (4400 1650);
PAINT SKYBLUE (4400 1650);
FORCEPROP 1 LAST VOLTAGE 4V
J 0
(4400 1850);
DISPLAY 0.723404 (4400 1850);
PAINT SKYBLUE (4400 1850);
FORCEPROP 1 LAST PART_NUMBER C95333-002
J 0
(4400 1700);
DISPLAY 0.617021 (4400 1700);
PAINT BLUE (4400 1700);
FORCEPROP 0 LAST GROUP PWR_MLCC_CAP
J 0
(4406 1612);
DISPLAY 0.638298 (4406 1612);
PAINT BROWN (4406 1612);
DISPLAY BOTH (4406 1612);
FORCEPROP 2 LAST CDS_LIB mstr_discrete
J 0
(4350 1850);
DISPLAY 1.936170 (4350 1850);
PAINT ORANGE (4350 1850);
DISPLAY INVISIBLE (4350 1850);
FORCEPROP 2 LAST CDS_LOCATION C6G3
J 0
(4400 1950);
DISPLAY 0.617021 (4400 1950);
PAINT AQUA (4400 1950);
DISPLAY INVISIBLE (4400 1950);
FORCEPROP 2 LAST ROOM VDDQ_ABC_PWR_VR
J 0
(4400 2000);
DISPLAY 1.446809 (4400 2000);
PAINT MONO (4400 2000);
DISPLAY INVISIBLE (4400 2000);
FORCEPROP 1 LAST PATH I6
J 0
(4400 2000);
DISPLAY 0.978723 (4400 2000);
PAINT WHITE (4400 2000);
DISPLAY INVISIBLE (4400 2000);
FORCEPROP 2 LAST BOM_COST PROC_VRD_VCCIN_CPU0
J 0
(4400 2000);
DISPLAY 1.446809 (4400 2000);
PAINT MONO (4400 2000);
DISPLAY INVISIBLE (4400 2000);
FORCEPROP 2 LAST SEC 1
J 0
(4400 2050);
DISPLAY 1.936170 (4400 2050);
PAINT MONO (4400 2050);
DISPLAY INVISIBLE (4400 2050);
FORCEPROP 2 LAST SEC_TYPE 0805LF
J 0
(4400 2050);
DISPLAY 1.936170 (4400 2050);
PAINT MONO (4400 2050);
DISPLAY INVISIBLE (4400 2050);
FORCEADD OFFPAGE..2
(3475 800);
FORCEPROP 2 LAST $XR0 215 
J 0
(3664 800);
DISPLAY 0.638298 (3664 800);
PAINT MONO (3664 800);
FORCEPROP 1 LAST COMMENT_BODY TRUE
J 0
(3430 705);
DISPLAY 1.723404 (3430 705);
PAINT GREEN (3430 705);
DISPLAY INVISIBLE (3430 705);
FORCEPROP 1 LAST OFFPAGE TRUE
J 0
(3800 675);
DISPLAY 1.723404 (3800 675);
PAINT GREEN (3800 675);
DISPLAY INVISIBLE (3800 675);
FORCEPROP 2 LAST ROOM VDDQ_ABC_PWR_VR
J 0
(3075 875);
DISPLAY 1.936170 (3075 875);
PAINT ORANGE (3075 875);
DISPLAY INVISIBLE (3075 875);
FORCEPROP 2 LAST CDS_LIB mstr_standard
J 0
(3475 800);
PAINT ORANGE (3475 800);
DISPLAY INVISIBLE (3475 800);
FORCEPROP 2 LAST PATH I61
J 0
(3655 875);
DISPLAY 1.361702 (3655 875);
PAINT ORANGE (3655 875);
DISPLAY INVISIBLE (3655 875);
FORCEPROP 2 LAST BOM_COST PROC_VRD_VCCIN_CPU0
J 0
(3675 850);
DISPLAY 1.446809 (3675 850);
PAINT MONO (3675 850);
DISPLAY INVISIBLE (3675 850);
FORCEADD OFFPAGE..2
(3475 475);
FORCEPROP 2 LAST $XR0 215 
J 0
(3664 475);
DISPLAY 0.638298 (3664 475);
PAINT MONO (3664 475);
FORCEPROP 1 LAST COMMENT_BODY TRUE
J 0
(3430 380);
DISPLAY 1.723404 (3430 380);
PAINT GREEN (3430 380);
DISPLAY INVISIBLE (3430 380);
FORCEPROP 1 LAST OFFPAGE TRUE
J 0
(3800 350);
DISPLAY 1.723404 (3800 350);
PAINT GREEN (3800 350);
DISPLAY INVISIBLE (3800 350);
FORCEPROP 2 LAST ROOM VDDQ_ABC_PWR_VR
J 0
(3075 550);
DISPLAY 1.936170 (3075 550);
PAINT ORANGE (3075 550);
DISPLAY INVISIBLE (3075 550);
FORCEPROP 2 LAST CDS_LIB mstr_standard
J 0
(3475 475);
PAINT ORANGE (3475 475);
DISPLAY INVISIBLE (3475 475);
FORCEPROP 2 LAST PATH I62
J 0
(3655 550);
DISPLAY 1.361702 (3655 550);
PAINT ORANGE (3655 550);
DISPLAY INVISIBLE (3655 550);
FORCEPROP 2 LAST BOM_COST PROC_VRD_VCCIN_CPU0
J 0
(3675 525);
DISPLAY 1.446809 (3675 525);
PAINT MONO (3675 525);
DISPLAY INVISIBLE (3675 525);
FORCEADD OFFPAGE..2
(3625 100);
FORCEPROP 2 LAST $XR1 215 
J 0
(3934 100);
DISPLAY 0.638298 (3934 100);
PAINT MONO (3934 100);
FORCEPROP 2 LAST $XR0 216 
J 0
(3814 100);
DISPLAY 0.638298 (3814 100);
PAINT MONO (3814 100);
FORCEPROP 1 LAST COMMENT_BODY TRUE
J 0
(3580 5);
DISPLAY 1.723404 (3580 5);
PAINT GREEN (3580 5);
DISPLAY INVISIBLE (3580 5);
FORCEPROP 1 LAST OFFPAGE TRUE
J 0
(3950 -25);
DISPLAY 1.723404 (3950 -25);
PAINT GREEN (3950 -25);
DISPLAY INVISIBLE (3950 -25);
FORCEPROP 2 LAST BOM_COST PROC_VRD_VCCIN_CPU0
J 0
(3825 150);
DISPLAY 1.446809 (3825 150);
PAINT MONO (3825 150);
DISPLAY INVISIBLE (3825 150);
FORCEPROP 2 LAST ROOM VDDQ_ABC_PWR_VR
J 0
(3225 175);
DISPLAY 1.936170 (3225 175);
PAINT ORANGE (3225 175);
DISPLAY INVISIBLE (3225 175);
FORCEPROP 2 LAST PATH I63
J 0
(3805 175);
DISPLAY 1.361702 (3805 175);
PAINT ORANGE (3805 175);
DISPLAY INVISIBLE (3805 175);
FORCEPROP 2 LAST CDS_LIB mstr_standard
J 0
(3625 100);
PAINT ORANGE (3625 100);
DISPLAY INVISIBLE (3625 100);
FORCEADD PVDDQ_ABC..1
(4400 -275);
FORCEPROP 3 LASTPIN (4400 -325) SIG_NAME PVDDQ_ABC\g
J 0
(4410 -315);
DISPLAY 0.659574 (4410 -315);
PAINT MONO (4410 -315);
DISPLAY INVISIBLE (4410 -315);
FORCEPROP 1 LAST HDL_POWER PVDDQ_ABC
J 1
(4400 -225);
DISPLAY 0.872340 (4400 -225);
PAINT GREEN (4400 -225);
DISPLAY INVISIBLE (4400 -225);
FORCEPROP 1 LAST BODY_TYPE PLUMBING
J 0
(4355 -318);
DISPLAY 0.340426 (4355 -318);
PAINT GREEN (4355 -318);
DISPLAY INVISIBLE (4355 -318);
FORCEPROP 2 LAST CDS_LIB mstr_symbols
J 0
(4400 -275);
PAINT ORANGE (4400 -275);
DISPLAY INVISIBLE (4400 -275);
FORCEPROP 1 LAST VOLTAGE 1.2V
J 0
(4355 -318);
DISPLAY 0.340426 (4355 -318);
PAINT SKYBLUE (4355 -318);
DISPLAY INVISIBLE (4355 -318);
FORCEPROP 2 LAST ROOM VDDQ_ABC_PWR_VR
J 0
(4400 -175);
DISPLAY 1.936170 (4400 -175);
PAINT ORANGE (4400 -175);
DISPLAY INVISIBLE (4400 -175);
FORCEPROP 2 LAST BOM_COST PROC_SOCKET 
J 0
(4400 -175);
DISPLAY 1.446809 (4400 -175);
PAINT MONO (4400 -175);
DISPLAY INVISIBLE (4400 -175);
FORCEPROP 1 LAST PATH I64
J 0
(4450 -250);
DISPLAY 0.872340 (4450 -250);
PAINT AQUA (4450 -250);
DISPLAY INVISIBLE (4450 -250);
FORCEADD CAP..1
(4400 -550);
FORCEPROP 1 LAST VOLTAGE 4V
J 0
(4450 -550);
DISPLAY 0.723404 (4450 -550);
PAINT SKYBLUE (4450 -550);
FORCEPROP 1 LASTPIN (4400 -650) $PN 2
J 0
(4410 -670);
DISPLAY 0.617021 (4410 -670);
PAINT ORANGE (4410 -670);
FORCEPROP 1 LAST MATERIAL X6S
J 0
(4450 -650);
DISPLAY 0.617021 (4450 -650);
PAINT SKYBLUE (4450 -650);
FORCEPROP 1 LAST TOLERANCE 20%
J 0
(4450 -600);
DISPLAY 0.617021 (4450 -600);
PAINT SKYBLUE (4450 -600);
FORCEPROP 1 LASTPIN (4400 -450) $PN 1
J 0
(4410 -470);
DISPLAY 0.617021 (4410 -470);
PAINT ORANGE (4410 -470);
FORCEPROP 1 LAST VALUE 22UF
J 0
(4450 -500);
DISPLAY 0.617021 (4450 -500);
PAINT SKYBLUE (4450 -500);
FORCEPROP 1 LAST LOCATION C7G27
J 0
(4450 -450);
DISPLAY 0.617021 (4450 -450);
PAINT AQUA (4450 -450);
FORCEPROP 0 LAST BOM_SS NOPOP
J 0
(4450 -850);
DISPLAY 0.638298 (4450 -850);
PAINT BROWN (4450 -850);
DISPLAY BOTH (4450 -850);
FORCEPROP 0 LAST GROUP PWR_MLCC_CAP
J 0
(4456 -788);
DISPLAY 0.638298 (4456 -788);
PAINT BROWN (4456 -788);
DISPLAY BOTH (4456 -788);
FORCEPROP 1 LAST PART_NUMBER C95333-002
J 0
(4450 -700);
DISPLAY 0.617021 (4450 -700);
PAINT BLUE (4450 -700);
FORCEPROP 1 LAST PACK_TYPE 0805LF
J 0
(4450 -750);
DISPLAY 0.617021 (4450 -750);
PAINT SKYBLUE (4450 -750);
FORCEPROP 2 LAST CDS_LIB mstr_discrete
J 0
(4400 -550);
PAINT ORANGE (4400 -550);
DISPLAY INVISIBLE (4400 -550);
FORCEPROP 2 LAST CDS_LOCATION C7G27
J 0
(4450 -450);
DISPLAY 0.617021 (4450 -450);
PAINT AQUA (4450 -450);
DISPLAY INVISIBLE (4450 -450);
FORCEPROP 2 LAST ROOM VDDQ_ABC_PWR_VR
J 0
(4450 -400);
DISPLAY 1.446809 (4450 -400);
PAINT MONO (4450 -400);
DISPLAY INVISIBLE (4450 -400);
FORCEPROP 1 LAST PATH I68
J 0
(4450 -400);
DISPLAY 1.319149 (4450 -400);
PAINT WHITE (4450 -400);
DISPLAY INVISIBLE (4450 -400);
FORCEPROP 2 LAST SEC 1
J 0
(4455 -325);
DISPLAY 0.680851 (4455 -325);
PAINT MONO (4455 -325);
DISPLAY INVISIBLE (4455 -325);
FORCEPROP 2 LAST SEC_TYPE 0805LF
J 0
(4450 -325);
DISPLAY 1.021277 (4450 -325);
PAINT ORANGE (4450 -325);
DISPLAY INVISIBLE (4450 -325);
FORCEPROP 2 LAST BOM_COST PROC_VRD_VCCIN_CPU0
J 0
(4450 -400);
DISPLAY 1.446809 (4450 -400);
PAINT MONO (4450 -400);
DISPLAY INVISIBLE (4450 -400);
FORCEADD GND..1
(4400 -800);
FORCEPROP 3 LASTPIN (4400 -750) SIG_NAME GND\g
J 0
(4410 -740);
DISPLAY 0.659574 (4410 -740);
PAINT MONO (4410 -740);
DISPLAY INVISIBLE (4410 -740);
FORCEPROP 1 LAST HDL_POWER GND
J 0
(4400 -650);
DISPLAY 1.723404 (4400 -650);
PAINT GREEN (4400 -650);
DISPLAY INVISIBLE (4400 -650);
FORCEPROP 1 LAST BODY_TYPE PLUMBING
J 0
(4355 -843);
DISPLAY 0.340426 (4355 -843);
PAINT GREEN (4355 -843);
DISPLAY INVISIBLE (4355 -843);
FORCEPROP 2 LAST ROOM VDDQ_ABC_PWR_VR
J 0
(3850 -725);
DISPLAY 1.936170 (3850 -725);
PAINT ORANGE (3850 -725);
DISPLAY INVISIBLE (3850 -725);
FORCEPROP 2 LAST BOM_COST PROC_VRD_VCCIN_CPU0
J 0
(4025 -725);
DISPLAY 1.446809 (4025 -725);
PAINT MONO (4025 -725);
DISPLAY INVISIBLE (4025 -725);
FORCEPROP 1 LAST VOLTAGE 0
J 0
(4400 -800);
PAINT SKYBLUE (4400 -800);
DISPLAY INVISIBLE (4400 -800);
FORCEPROP 2 LAST CDS_LIB mstr_symbols
J 0
(4400 -800);
PAINT ORANGE (4400 -800);
DISPLAY INVISIBLE (4400 -800);
FORCEPROP 1 LAST PATH I69
J 0
(4475 -800);
DISPLAY 1.170213 (4475 -800);
PAINT AQUA (4475 -800);
DISPLAY INVISIBLE (4475 -800);
FORCEPROP 1 LAST SIZE 1B
J 0
(4475 -850);
DISPLAY 1.723404 (4475 -850);
PAINT GREEN (4475 -850);
DISPLAY INVISIBLE (4475 -850);
FORCEADD GND..1
(4350 1625);
FORCEPROP 3 LASTPIN (4350 1675) SIG_NAME GND\g
J 0
(4360 1685);
DISPLAY 0.659574 (4360 1685);
PAINT MONO (4360 1685);
DISPLAY INVISIBLE (4360 1685);
FORCEPROP 1 LAST HDL_POWER GND
J 0
(4350 1775);
DISPLAY 1.723404 (4350 1775);
PAINT GREEN (4350 1775);
DISPLAY INVISIBLE (4350 1775);
FORCEPROP 1 LAST BODY_TYPE PLUMBING
J 0
(4305 1582);
DISPLAY 0.340426 (4305 1582);
PAINT GREEN (4305 1582);
DISPLAY INVISIBLE (4305 1582);
FORCEPROP 2 LAST ROOM VDDQ_ABC_PWR_VR
J 0
(3800 1700);
DISPLAY 1.936170 (3800 1700);
PAINT ORANGE (3800 1700);
DISPLAY INVISIBLE (3800 1700);
FORCEPROP 1 LAST PATH I7
J 0
(4425 1625);
DISPLAY 0.893617 (4425 1625);
PAINT AQUA (4425 1625);
DISPLAY INVISIBLE (4425 1625);
FORCEPROP 2 LAST CDS_LIB mstr_symbols
J 0
(4350 1625);
DISPLAY 1.936170 (4350 1625);
PAINT ORANGE (4350 1625);
DISPLAY INVISIBLE (4350 1625);
FORCEPROP 1 LAST SIZE 1B
J 0
(4425 1575);
DISPLAY 1.723404 (4425 1575);
PAINT GREEN (4425 1575);
DISPLAY INVISIBLE (4425 1575);
FORCEPROP 1 LAST VOLTAGE 0
J 0
(4350 1625);
PAINT SKYBLUE (4350 1625);
DISPLAY INVISIBLE (4350 1625);
FORCEPROP 2 LAST BOM_COST PROC_VRD_VCCIN_CPU0
J 0
(3975 1700);
DISPLAY 1.446809 (3975 1700);
PAINT MONO (3975 1700);
DISPLAY INVISIBLE (3975 1700);
FORCEADD GND..1
(2450 -825);
FORCEPROP 3 LASTPIN (2450 -775) SIG_NAME GND\g
J 0
(2460 -765);
DISPLAY 0.659574 (2460 -765);
PAINT MONO (2460 -765);
DISPLAY INVISIBLE (2460 -765);
FORCEPROP 1 LAST HDL_POWER GND
J 0
(2450 -675);
DISPLAY 1.723404 (2450 -675);
PAINT GREEN (2450 -675);
DISPLAY INVISIBLE (2450 -675);
FORCEPROP 1 LAST BODY_TYPE PLUMBING
J 0
(2405 -868);
DISPLAY 0.340426 (2405 -868);
PAINT GREEN (2405 -868);
DISPLAY INVISIBLE (2405 -868);
FORCEPROP 2 LAST ROOM :VCCIN_CPU0_PWR_VR
J 0
(1900 -750);
DISPLAY 1.936170 (1900 -750);
PAINT ORANGE (1900 -750);
DISPLAY INVISIBLE (1900 -750);
FORCEPROP 2 LAST BOM_COST PROC_VRD_VCCIN_CPU0
J 0
(2075 -750);
DISPLAY 1.446809 (2075 -750);
PAINT MONO (2075 -750);
DISPLAY INVISIBLE (2075 -750);
FORCEPROP 1 LAST VOLTAGE 0
J 0
(2450 -825);
PAINT SKYBLUE (2450 -825);
DISPLAY INVISIBLE (2450 -825);
FORCEPROP 1 LAST SIZE 1B
J 0
(2525 -875);
DISPLAY 1.723404 (2525 -875);
PAINT GREEN (2525 -875);
DISPLAY INVISIBLE (2525 -875);
FORCEPROP 2 LAST CDS_LIB mstr_symbols
J 0
(2450 -825);
PAINT ORANGE (2450 -825);
DISPLAY INVISIBLE (2450 -825);
FORCEPROP 1 LAST PATH I70
J 0
(2525 -825);
DISPLAY 1.170213 (2525 -825);
PAINT AQUA (2525 -825);
DISPLAY INVISIBLE (2525 -825);
FORCEADD CAP..1
(50 200);
FORCEPROP 1 LAST PACK_TYPE 0402
J 0
(100 0);
DISPLAY 0.617021 (100 0);
PAINT SKYBLUE (100 0);
FORCEPROP 1 LAST MATERIAL X7R
J 0
(100 100);
DISPLAY 0.617021 (100 100);
PAINT SKYBLUE (100 100);
FORCEPROP 1 LASTPIN (50 100) $PN 2
J 0
(60 80);
DISPLAY 0.617021 (60 80);
PAINT ORANGE (60 80);
FORCEPROP 1 LAST TOLERANCE 10%
J 0
(100 150);
DISPLAY 0.617021 (100 150);
PAINT SKYBLUE (100 150);
FORCEPROP 1 LAST VOLTAGE 16V
J 0
(100 200);
DISPLAY 0.617021 (100 200);
PAINT SKYBLUE (100 200);
FORCEPROP 1 LAST LOCATION C7G41
J 0
(100 300);
DISPLAY 0.617021 (100 300);
PAINT AQUA (100 300);
FORCEPROP 1 LASTPIN (50 300) $PN 1
J 0
(60 280);
DISPLAY 0.617021 (60 280);
PAINT ORANGE (60 280);
FORCEPROP 1 LAST PART_NUMBER A36096-155
J 0
(100 50);
DISPLAY 0.617021 (100 50);
PAINT BLUE (100 50);
FORCEPROP 1 LAST VALUE 0.22UF
J 0
(100 250);
DISPLAY 0.617021 (100 250);
PAINT SKYBLUE (100 250);
FORCEPROP 0 LAST BOM_SS NOPOP
J 0
(250 225);
DISPLAY 0.638298 (250 225);
PAINT BROWN (250 225);
DISPLAY BOTH (250 225);
FORCEPROP 2 LAST ROOM VDDQ_ABC_PWR_VR
J 0
(100 350);
DISPLAY 1.361702 (100 350);
PAINT ORANGE (100 350);
DISPLAY INVISIBLE (100 350);
FORCEPROP 1 LAST PATH I72
J 0
(100 350);
DISPLAY 1.319149 (100 350);
PAINT WHITE (100 350);
DISPLAY INVISIBLE (100 350);
FORCEPROP 2 LAST SEC_TYPE 0402
J 0
(100 425);
DISPLAY 1.021277 (100 425);
PAINT ORANGE (100 425);
DISPLAY INVISIBLE (100 425);
FORCEPROP 2 LAST SEC 1
J 0
(100 425);
DISPLAY 0.680851 (100 425);
PAINT MONO (100 425);
DISPLAY INVISIBLE (100 425);
FORCEPROP 2 LAST CDS_LOCATION C7G41
J 0
(100 300);
DISPLAY 0.617021 (100 300);
PAINT AQUA (100 300);
DISPLAY INVISIBLE (100 300);
FORCEPROP 2 LAST CDS_LIB mstr_discrete
J 0
(50 200);
PAINT ORANGE (50 200);
DISPLAY INVISIBLE (50 200);
FORCEADD CAP..1
(-825 175);
FORCEPROP 0 LAST BOM_SS NOPOP
J 0
(-800 -125);
DISPLAY 0.638298 (-800 -125);
PAINT BROWN (-800 -125);
DISPLAY BOTH (-800 -125);
FORCEPROP 1 LAST PACK_TYPE 0402
J 0
(-775 -25);
DISPLAY 0.617021 (-775 -25);
PAINT SKYBLUE (-775 -25);
FORCEPROP 1 LASTPIN (-825 75) $PN 2
J 0
(-815 55);
DISPLAY 0.617021 (-815 55);
PAINT ORANGE (-815 55);
FORCEPROP 1 LASTPIN (-825 275) $PN 1
J 0
(-815 255);
DISPLAY 0.617021 (-815 255);
PAINT ORANGE (-815 255);
FORCEPROP 1 LAST LOCATION C7G40
J 0
(-775 275);
DISPLAY 0.617021 (-775 275);
PAINT AQUA (-775 275);
FORCEPROP 1 LAST TOLERANCE 10%
J 0
(-775 125);
DISPLAY 0.617021 (-775 125);
PAINT SKYBLUE (-775 125);
FORCEPROP 1 LAST VALUE 1.0UF
J 0
(-775 225);
DISPLAY 0.617021 (-775 225);
PAINT SKYBLUE (-775 225);
FORCEPROP 1 LAST VOLTAGE 16V
J 0
(-775 175);
DISPLAY 0.617021 (-775 175);
PAINT SKYBLUE (-775 175);
FORCEPROP 1 LAST MATERIAL X6S
J 0
(-775 75);
DISPLAY 0.617021 (-775 75);
PAINT SKYBLUE (-775 75);
FORCEPROP 1 LAST PART_NUMBER D97712-011
J 0
(-775 25);
DISPLAY 0.617021 (-775 25);
PAINT BLUE (-775 25);
FORCEPROP 2 LAST CDS_LIB mstr_discrete
J 0
(-825 175);
PAINT ORANGE (-825 175);
DISPLAY INVISIBLE (-825 175);
FORCEPROP 2 LAST CDS_LOCATION C7G40
J 0
(-775 275);
DISPLAY 0.617021 (-775 275);
PAINT AQUA (-775 275);
DISPLAY INVISIBLE (-775 275);
FORCEPROP 2 LAST ROOM VDDQ_ABC_PWR_VR
J 0
(-775 325);
DISPLAY 1.361702 (-775 325);
PAINT ORANGE (-775 325);
DISPLAY INVISIBLE (-775 325);
FORCEPROP 1 LAST PATH I77
J 0
(-775 325);
DISPLAY 1.319149 (-775 325);
PAINT WHITE (-775 325);
DISPLAY INVISIBLE (-775 325);
FORCEPROP 2 LAST SEC 1
J 0
(-775 400);
DISPLAY 0.680851 (-775 400);
PAINT MONO (-775 400);
DISPLAY INVISIBLE (-775 400);
FORCEPROP 2 LAST SEC_TYPE 0402
J 0
(-775 400);
DISPLAY 1.021277 (-775 400);
PAINT ORANGE (-775 400);
DISPLAY INVISIBLE (-775 400);
FORCEADD CAP_A..1
(-1075 175);
FORCEPROP 1 LAST PACK_TYPE 0402V
J 0
(-1025 -25);
DISPLAY 0.617021 (-1025 -25);
PAINT SKYBLUE (-1025 -25);
FORCEPROP 1 LASTPIN (-1075 75) $PN 2
J 0
(-1065 55);
DISPLAY 0.617021 (-1065 55);
PAINT ORANGE (-1065 55);
FORCEPROP 1 LASTPIN (-1075 275) $PN 1
J 0
(-1065 255);
DISPLAY 0.617021 (-1065 255);
PAINT ORANGE (-1065 255);
FORCEPROP 1 LAST PART_NUMBER A36096-030
J 0
(-1025 25);
DISPLAY 0.617021 (-1025 25);
PAINT BLUE (-1025 25);
FORCEPROP 1 LAST MATERIAL X7R
J 0
(-1025 75);
DISPLAY 0.617021 (-1025 75);
PAINT SKYBLUE (-1025 75);
FORCEPROP 1 LAST TOLERANCE 10%
J 0
(-1025 125);
DISPLAY 0.617021 (-1025 125);
PAINT SKYBLUE (-1025 125);
FORCEPROP 1 LAST VOLTAGE 16V
J 0
(-1025 175);
DISPLAY 0.617021 (-1025 175);
PAINT SKYBLUE (-1025 175);
FORCEPROP 1 LAST VALUE 0.1UF
J 0
(-1025 225);
DISPLAY 0.617021 (-1025 225);
PAINT SKYBLUE (-1025 225);
FORCEPROP 1 LAST LOCATION C7G36
J 0
(-1025 275);
DISPLAY 0.617021 (-1025 275);
PAINT AQUA (-1025 275);
FORCEPROP 2 LAST SEC 1
J 0
(-1025 400);
DISPLAY 0.680851 (-1025 400);
PAINT MONO (-1025 400);
DISPLAY INVISIBLE (-1025 400);
FORCEPROP 2 LAST SEC_TYPE 0402V
J 0
(-1025 400);
DISPLAY 1.021277 (-1025 400);
PAINT ORANGE (-1025 400);
DISPLAY INVISIBLE (-1025 400);
FORCEPROP 2 LAST CDS_SEC 1
J 0
(-1025 325);
PAINT ORANGE (-1025 325);
DISPLAY INVISIBLE (-1025 325);
FORCEPROP 2 LAST ROOM VDDQ_ABC_PWR_VR
J 0
(-1025 325);
DISPLAY 1.361702 (-1025 325);
PAINT ORANGE (-1025 325);
DISPLAY INVISIBLE (-1025 325);
FORCEPROP 1 LAST PATH I78
J 0
(-1025 325);
DISPLAY 0.978723 (-1025 325);
PAINT WHITE (-1025 325);
DISPLAY INVISIBLE (-1025 325);
FORCEPROP 2 LAST CDS_LIB dev_discrete
J 0
(-1075 175);
PAINT ORANGE (-1075 175);
DISPLAY INVISIBLE (-1075 175);
FORCEPROP 2 LAST CDS_LOCATION C7G36
J 0
(-1025 275);
DISPLAY 0.617021 (-1025 275);
PAINT AQUA (-1025 275);
DISPLAY INVISIBLE (-1025 275);
FORCEADD CAP..1
(-1325 175);
FORCEPROP 1 LAST PACK_TYPE 0402
J 0
(-1300 -25);
DISPLAY 0.617021 (-1300 -25);
PAINT SKYBLUE (-1300 -25);
FORCEPROP 1 LASTPIN (-1325 75) $PN 2
J 0
(-1315 105);
DISPLAY 0.617021 (-1315 105);
PAINT ORANGE (-1315 105);
FORCEPROP 1 LASTPIN (-1325 275) $PN 1
J 0
(-1315 255);
DISPLAY 0.617021 (-1315 255);
PAINT ORANGE (-1315 255);
FORCEPROP 1 LAST VALUE 1.0UF
J 0
(-1275 225);
DISPLAY 0.617021 (-1275 225);
PAINT SKYBLUE (-1275 225);
FORCEPROP 1 LAST VOLTAGE 16V
J 0
(-1275 175);
DISPLAY 0.617021 (-1275 175);
PAINT SKYBLUE (-1275 175);
FORCEPROP 1 LAST MATERIAL X6S
J 0
(-1275 75);
DISPLAY 0.617021 (-1275 75);
PAINT SKYBLUE (-1275 75);
FORCEPROP 1 LAST TOLERANCE 10%
J 0
(-1275 125);
DISPLAY 0.617021 (-1275 125);
PAINT SKYBLUE (-1275 125);
FORCEPROP 1 LAST LOCATION C7G30
J 0
(-1275 275);
DISPLAY 0.617021 (-1275 275);
PAINT AQUA (-1275 275);
FORCEPROP 1 LAST PART_NUMBER D97712-011
J 0
(-1300 25);
DISPLAY 0.617021 (-1300 25);
PAINT BLUE (-1300 25);
FORCEPROP 2 LAST CDS_LIB mstr_discrete
J 0
(-1325 175);
PAINT ORANGE (-1325 175);
DISPLAY INVISIBLE (-1325 175);
FORCEPROP 2 LAST CDS_LOCATION C7G30
J 0
(-1275 275);
DISPLAY 0.617021 (-1275 275);
PAINT AQUA (-1275 275);
DISPLAY INVISIBLE (-1275 275);
FORCEPROP 2 LAST SEC_TYPE 0402
J 0
(-1275 400);
DISPLAY 1.021277 (-1275 400);
PAINT ORANGE (-1275 400);
DISPLAY INVISIBLE (-1275 400);
FORCEPROP 2 LAST SEC 1
J 0
(-1275 400);
DISPLAY 0.680851 (-1275 400);
PAINT MONO (-1275 400);
DISPLAY INVISIBLE (-1275 400);
FORCEPROP 1 LAST PATH I79
J 0
(-1275 325);
DISPLAY 1.319149 (-1275 325);
PAINT WHITE (-1275 325);
DISPLAY INVISIBLE (-1275 325);
FORCEPROP 2 LAST ROOM VDDQ_ABC_PWR_VR
J 0
(-1275 325);
DISPLAY 1.361702 (-1275 325);
PAINT ORANGE (-1275 325);
DISPLAY INVISIBLE (-1275 325);
FORCEADD CAP..1
(-1550 175);
FORCEPROP 1 LAST PACK_TYPE 0805
J 0
(-1500 -25);
DISPLAY 0.617021 (-1500 -25);
PAINT SKYBLUE (-1500 -25);
FORCEPROP 1 LASTPIN (-1550 75) $PN 2
J 0
(-1540 105);
DISPLAY 0.617021 (-1540 105);
PAINT ORANGE (-1540 105);
FORCEPROP 1 LASTPIN (-1550 275) $PN 1
J 0
(-1540 255);
DISPLAY 0.617021 (-1540 255);
PAINT ORANGE (-1540 255);
FORCEPROP 1 LAST VOLTAGE 16V
J 0
(-1500 175);
DISPLAY 0.617021 (-1500 175);
PAINT SKYBLUE (-1500 175);
FORCEPROP 1 LAST TOLERANCE 10%
J 0
(-1500 125);
DISPLAY 0.617021 (-1500 125);
PAINT SKYBLUE (-1500 125);
FORCEPROP 1 LAST MATERIAL X6S
J 0
(-1500 75);
DISPLAY 0.617021 (-1500 75);
PAINT SKYBLUE (-1500 75);
FORCEPROP 1 LAST VALUE 10UF
J 0
(-1500 225);
DISPLAY 0.617021 (-1500 225);
PAINT SKYBLUE (-1500 225);
FORCEPROP 1 LAST LOCATION C3U9
J 0
(-1500 275);
DISPLAY 0.617021 (-1500 275);
PAINT AQUA (-1500 275);
FORCEPROP 1 LAST PART_NUMBER C95333-007
J 0
(-1500 25);
DISPLAY 0.617021 (-1500 25);
PAINT BLUE (-1500 25);
FORCEPROP 2 LAST CDS_LOCATION C3U9
J 0
(-1500 275);
DISPLAY 0.617021 (-1500 275);
PAINT AQUA (-1500 275);
DISPLAY INVISIBLE (-1500 275);
FORCEPROP 2 LAST CDS_LIB mstr_discrete
J 0
(-1550 175);
PAINT ORANGE (-1550 175);
DISPLAY INVISIBLE (-1550 175);
FORCEPROP 2 LAST ROOM VDDQ_ABC_PWR_VR
J 0
(-1500 325);
DISPLAY 1.361702 (-1500 325);
PAINT ORANGE (-1500 325);
DISPLAY INVISIBLE (-1500 325);
FORCEPROP 1 LAST PATH I80
J 0
(-1500 325);
DISPLAY 1.319149 (-1500 325);
PAINT WHITE (-1500 325);
DISPLAY INVISIBLE (-1500 325);
FORCEPROP 2 LAST SEC 1
J 0
(-1500 400);
DISPLAY 0.680851 (-1500 400);
PAINT MONO (-1500 400);
DISPLAY INVISIBLE (-1500 400);
FORCEPROP 2 LAST SEC_TYPE 0805
J 0
(-1500 400);
DISPLAY 1.021277 (-1500 400);
PAINT ORANGE (-1500 400);
DISPLAY INVISIBLE (-1500 400);
FORCEADD CAP..1
(-1800 175);
FORCEPROP 1 LAST PACK_TYPE 0805
J 0
(-1750 -25);
DISPLAY 0.617021 (-1750 -25);
PAINT SKYBLUE (-1750 -25);
FORCEPROP 1 LAST TOLERANCE 10%
J 0
(-1750 125);
DISPLAY 0.617021 (-1750 125);
PAINT SKYBLUE (-1750 125);
FORCEPROP 1 LAST MATERIAL X6S
J 0
(-1750 75);
DISPLAY 0.617021 (-1750 75);
PAINT SKYBLUE (-1750 75);
FORCEPROP 1 LASTPIN (-1800 75) $PN 2
J 0
(-1790 80);
DISPLAY 0.617021 (-1790 80);
PAINT ORANGE (-1790 80);
FORCEPROP 1 LAST VALUE 10UF
J 0
(-1750 225);
DISPLAY 0.617021 (-1750 225);
PAINT SKYBLUE (-1750 225);
FORCEPROP 1 LAST VOLTAGE 16V
J 0
(-1750 175);
DISPLAY 0.617021 (-1750 175);
PAINT SKYBLUE (-1750 175);
FORCEPROP 1 LASTPIN (-1800 275) $PN 1
J 0
(-1790 255);
DISPLAY 0.617021 (-1790 255);
PAINT ORANGE (-1790 255);
FORCEPROP 1 LAST LOCATION C3U7
J 0
(-1750 275);
DISPLAY 0.617021 (-1750 275);
PAINT AQUA (-1750 275);
FORCEPROP 1 LAST PART_NUMBER C95333-007
J 0
(-1750 25);
DISPLAY 0.617021 (-1750 25);
PAINT BLUE (-1750 25);
FORCEPROP 2 LAST ROOM VDDQ_ABC_PWR_VR
J 0
(-1750 325);
DISPLAY 1.361702 (-1750 325);
PAINT ORANGE (-1750 325);
DISPLAY INVISIBLE (-1750 325);
FORCEPROP 1 LAST PATH I81
J 0
(-1750 325);
DISPLAY 1.319149 (-1750 325);
PAINT WHITE (-1750 325);
DISPLAY INVISIBLE (-1750 325);
FORCEPROP 2 LAST SEC 1
J 0
(-1750 400);
DISPLAY 0.680851 (-1750 400);
PAINT MONO (-1750 400);
DISPLAY INVISIBLE (-1750 400);
FORCEPROP 2 LAST SEC_TYPE 0805
J 0
(-1750 400);
DISPLAY 1.021277 (-1750 400);
PAINT ORANGE (-1750 400);
DISPLAY INVISIBLE (-1750 400);
FORCEPROP 2 LAST CDS_LOCATION C3U7
J 0
(-1750 275);
DISPLAY 0.617021 (-1750 275);
PAINT AQUA (-1750 275);
DISPLAY INVISIBLE (-1750 275);
FORCEPROP 2 LAST CDS_LIB mstr_discrete
J 0
(-1800 175);
PAINT ORANGE (-1800 175);
DISPLAY INVISIBLE (-1800 175);
FORCEADD OFFPAGE..1
(450 -175);
FORCEPROP 2 LAST $XR0 215 
J 0
(168 -175);
DISPLAY 0.638298 (168 -175);
PAINT MONO (168 -175);
FORCEPROP 2 LAST PATH I82
J 0
(505 -100);
DISPLAY 1.361702 (505 -100);
PAINT ORANGE (505 -100);
DISPLAY INVISIBLE (505 -100);
FORCEPROP 2 LAST CDS_LIB mstr_standard
J 0
(450 -175);
PAINT ORANGE (450 -175);
DISPLAY INVISIBLE (450 -175);
FORCEPROP 2 LAST ROOM VDDQ_ABC_PWR_VR
J 0
(50 -100);
DISPLAY 1.936170 (50 -100);
PAINT ORANGE (50 -100);
DISPLAY INVISIBLE (50 -100);
FORCEPROP 2 LAST BOM_COST PROC_VRD_VCCIN_CPU0
J 0
(200 -125);
DISPLAY 1.446809 (200 -125);
PAINT MONO (200 -125);
DISPLAY INVISIBLE (200 -125);
FORCEPROP 1 LAST OFFPAGE TRUE
J 0
(775 -300);
DISPLAY 1.680851 (775 -300);
PAINT GREEN (775 -300);
DISPLAY INVISIBLE (775 -300);
FORCEPROP 1 LAST COMMENT_BODY TRUE
J 0
(575 -275);
DISPLAY 1.680851 (575 -275);
PAINT GREEN (575 -275);
DISPLAY INVISIBLE (575 -275);
FORCEADD VCC_CORE..1
(-2050 475);
FORCEPROP 3 LASTPIN (-2050 425) SIG_NAME VR_FET_SW_P12V_STBY_PVDDQ_ABC\g
J 0
(-2040 435);
DISPLAY 0.659574 (-2040 435);
PAINT MONO (-2040 435);
DISPLAY INVISIBLE (-2040 435);
FORCEPROP 1 LAST HDL_POWER VR_FET_SW_P12V_STBY_PVDDQ_ABC
J 1
(-1975 525);
DISPLAY 0.617021 (-1975 525);
PAINT GREEN (-1975 525);
FORCEPROP 2 LAST CDS_LIB mstr_symbols
J 0
(-2050 475);
PAINT ORANGE (-2050 475);
DISPLAY INVISIBLE (-2050 475);
FORCEPROP 1 LAST PATH I83
J 0
(-2000 500);
DISPLAY 1.170213 (-2000 500);
PAINT AQUA (-2000 500);
DISPLAY INVISIBLE (-2000 500);
FORCEADD CAP..1
(-2050 175);
FORCEPROP 1 LAST PACK_TYPE 0805
J 0
(-2000 -25);
DISPLAY 0.617021 (-2000 -25);
PAINT SKYBLUE (-2000 -25);
FORCEPROP 1 LAST MATERIAL X6S
J 0
(-2000 75);
DISPLAY 0.617021 (-2000 75);
PAINT SKYBLUE (-2000 75);
FORCEPROP 1 LAST VALUE 10UF
J 0
(-2000 225);
DISPLAY 0.617021 (-2000 225);
PAINT SKYBLUE (-2000 225);
FORCEPROP 1 LAST TOLERANCE 10%
J 0
(-2000 125);
DISPLAY 0.617021 (-2000 125);
PAINT SKYBLUE (-2000 125);
FORCEPROP 1 LAST VOLTAGE 16V
J 0
(-2000 175);
DISPLAY 0.617021 (-2000 175);
PAINT SKYBLUE (-2000 175);
FORCEPROP 1 LASTPIN (-2050 75) $PN 2
J 0
(-2040 80);
DISPLAY 0.617021 (-2040 80);
PAINT ORANGE (-2040 80);
FORCEPROP 1 LASTPIN (-2050 275) $PN 1
J 0
(-2040 255);
DISPLAY 0.617021 (-2040 255);
PAINT ORANGE (-2040 255);
FORCEPROP 1 LAST LOCATION C3U6
J 0
(-2000 275);
DISPLAY 0.617021 (-2000 275);
PAINT AQUA (-2000 275);
FORCEPROP 1 LAST PART_NUMBER C95333-007
J 0
(-2000 25);
DISPLAY 0.617021 (-2000 25);
PAINT BLUE (-2000 25);
FORCEPROP 2 LAST CDS_LIB mstr_discrete
J 0
(-2050 175);
PAINT ORANGE (-2050 175);
DISPLAY INVISIBLE (-2050 175);
FORCEPROP 2 LAST CDS_LOCATION C3U6
J 0
(-2000 275);
DISPLAY 0.617021 (-2000 275);
PAINT AQUA (-2000 275);
DISPLAY INVISIBLE (-2000 275);
FORCEPROP 1 LAST PATH I84
J 0
(-2000 325);
DISPLAY 1.319149 (-2000 325);
PAINT WHITE (-2000 325);
DISPLAY INVISIBLE (-2000 325);
FORCEPROP 2 LAST ROOM VDDQ_ABC_PWR_VR
J 0
(-2000 325);
DISPLAY 1.361702 (-2000 325);
PAINT ORANGE (-2000 325);
DISPLAY INVISIBLE (-2000 325);
FORCEPROP 2 LAST SEC_TYPE 0805
J 0
(-2000 400);
DISPLAY 1.021277 (-2000 400);
PAINT ORANGE (-2000 400);
DISPLAY INVISIBLE (-2000 400);
FORCEPROP 2 LAST SEC 1
J 0
(-2000 400);
DISPLAY 0.680851 (-2000 400);
PAINT MONO (-2000 400);
DISPLAY INVISIBLE (-2000 400);
FORCEADD GND..1
(-2050 -175);
FORCEPROP 3 LASTPIN (-2050 -125) SIG_NAME GND\g
J 0
(-2040 -115);
DISPLAY 0.659574 (-2040 -115);
PAINT MONO (-2040 -115);
DISPLAY INVISIBLE (-2040 -115);
FORCEPROP 2 LAST ROOM VDDQ_ABC_PWR_VR
J 0
(-2600 -100);
DISPLAY 1.936170 (-2600 -100);
PAINT ORANGE (-2600 -100);
DISPLAY INVISIBLE (-2600 -100);
FORCEPROP 2 LAST BOM_COST PROC_VRD_VCCIN_CPU0
J 0
(-2425 -100);
DISPLAY 1.446809 (-2425 -100);
PAINT MONO (-2425 -100);
DISPLAY INVISIBLE (-2425 -100);
FORCEPROP 1 LAST VOLTAGE 0
J 0
(-2050 -175);
PAINT SKYBLUE (-2050 -175);
DISPLAY INVISIBLE (-2050 -175);
FORCEPROP 2 LAST CDS_LIB mstr_symbols
J 0
(-2050 -175);
PAINT ORANGE (-2050 -175);
DISPLAY INVISIBLE (-2050 -175);
FORCEPROP 1 LAST SIZE 1B
J 0
(-1975 -225);
DISPLAY 1.723404 (-1975 -225);
PAINT GREEN (-1975 -225);
DISPLAY INVISIBLE (-1975 -225);
FORCEPROP 1 LAST PATH I85
J 0
(-1975 -175);
DISPLAY 1.170213 (-1975 -175);
PAINT AQUA (-1975 -175);
DISPLAY INVISIBLE (-1975 -175);
FORCEPROP 1 LAST BODY_TYPE PLUMBING
J 0
(-2095 -218);
DISPLAY 0.340426 (-2095 -218);
PAINT GREEN (-2095 -218);
DISPLAY INVISIBLE (-2095 -218);
FORCEPROP 1 LAST HDL_POWER GND
J 0
(-2050 -25);
DISPLAY 1.723404 (-2050 -25);
PAINT GREEN (-2050 -25);
DISPLAY INVISIBLE (-2050 -25);
FORCEADD VCC_CORE..1
(-1625 2900);
FORCEPROP 3 LASTPIN (-1625 2850) SIG_NAME VR_FET_SW_P12V_STBY_PVDDQ_ABC\g
J 0
(-1615 2860);
DISPLAY 0.659574 (-1615 2860);
PAINT MONO (-1615 2860);
DISPLAY INVISIBLE (-1615 2860);
FORCEPROP 1 LAST HDL_POWER VR_FET_SW_P12V_STBY_PVDDQ_ABC
J 1
(-1525 2950);
DISPLAY 0.617021 (-1525 2950);
PAINT GREEN (-1525 2950);
FORCEPROP 2 LAST CDS_LIB mstr_symbols
J 0
(-1625 2900);
PAINT ORANGE (-1625 2900);
DISPLAY INVISIBLE (-1625 2900);
FORCEPROP 1 LAST PATH I86
J 0
(-1575 2925);
DISPLAY 1.170213 (-1575 2925);
PAINT AQUA (-1575 2925);
DISPLAY INVISIBLE (-1575 2925);
FORCEADD P5V_STBY..1
(350 3250);
FORCEPROP 3 LASTPIN (350 3200) SIG_NAME P5V_STBY\g
J 0
(360 3210);
DISPLAY 0.659574 (360 3210);
PAINT MONO (360 3210);
DISPLAY INVISIBLE (360 3210);
FORCEPROP 1 LAST HDL_POWER P5V_STBY
J 0
(50 3125);
DISPLAY 0.872340 (50 3125);
PAINT ORANGE (50 3125);
DISPLAY INVISIBLE (50 3125);
FORCEPROP 1 LAST BODY_TYPE PLUMBING
J 0
(305 3207);
DISPLAY 0.340426 (305 3207);
PAINT GREEN (305 3207);
DISPLAY INVISIBLE (305 3207);
FORCEPROP 1 LAST VOLTAGE 5.0V
J 0
(305 3207);
DISPLAY 0.340426 (305 3207);
PAINT SKYBLUE (305 3207);
DISPLAY INVISIBLE (305 3207);
FORCEPROP 2 LAST CDS_LIB mstr_symbols
J 0
(350 3250);
PAINT ORANGE (350 3250);
DISPLAY INVISIBLE (350 3250);
FORCEPROP 1 LAST PATH I87
J 0
(395 3252);
DISPLAY 0.340426 (395 3252);
PAINT GREEN (395 3252);
DISPLAY INVISIBLE (395 3252);
FORCEPROP 1 LAST SIZE 1B
J 0
(395 3272);
DISPLAY 0.340426 (395 3272);
PAINT GREEN (395 3272);
DISPLAY INVISIBLE (395 3272);
FORCEADD P5V_STBY..1
(500 900);
FORCEPROP 3 LASTPIN (500 850) SIG_NAME P5V_STBY\g
J 0
(510 860);
DISPLAY 0.659574 (510 860);
PAINT MONO (510 860);
DISPLAY INVISIBLE (510 860);
FORCEPROP 1 LAST HDL_POWER P5V_STBY
J 0
(200 775);
DISPLAY 0.872340 (200 775);
PAINT ORANGE (200 775);
DISPLAY INVISIBLE (200 775);
FORCEPROP 1 LAST BODY_TYPE PLUMBING
J 0
(455 857);
DISPLAY 0.340426 (455 857);
PAINT GREEN (455 857);
DISPLAY INVISIBLE (455 857);
FORCEPROP 1 LAST VOLTAGE 5.0V
J 0
(455 857);
DISPLAY 0.340426 (455 857);
PAINT SKYBLUE (455 857);
DISPLAY INVISIBLE (455 857);
FORCEPROP 1 LAST SIZE 1B
J 0
(545 922);
DISPLAY 0.340426 (545 922);
PAINT GREEN (545 922);
DISPLAY INVISIBLE (545 922);
FORCEPROP 2 LAST CDS_LIB mstr_symbols
J 0
(500 900);
PAINT ORANGE (500 900);
DISPLAY INVISIBLE (500 900);
FORCEPROP 1 LAST PATH I88
J 0
(545 902);
DISPLAY 0.340426 (545 902);
PAINT GREEN (545 902);
DISPLAY INVISIBLE (545 902);
FORCEADD DNS..2
(4680 45);
PAINT RED (4680 45);
FORCEPROP 1 LAST COMMENT_BODY TRUE
R 1
J 0
(4755 -180);
DISPLAY 0.872340 (4755 -180);
PAINT GREEN (4755 -180);
DISPLAY INVISIBLE (4755 -180);
FORCEPROP 2 LAST CDS_LIB mstr_misc
J 0
(4680 45);
PAINT ORANGE (4680 45);
DISPLAY INVISIBLE (4680 45);
FORCEADD INTEL_CORP_BPAGE..1
(5300 -1650);
FORCEPROP 1 LAST CDS_CON_LAST_MODIFIED Fri Jun 16 17:49:18 2017
J 0
(3875 -1325);
DISPLAY 1.936170 (3875 -1325);
PAINT GREEN (3875 -1325);
DISPLAY INVISIBLE (3875 -1325);
FORCEPROP 2 LAST CUSTOM_TXT_CDS <XR_PAGE_TITLE>
J 0
(-2590 3600);
DISPLAY 0.638298 (-2590 3600);
PAINT PINK (-2590 3600);
DISPLAY INVISIBLE (-2590 3600);
FORCEPROP 2 LAST CUSTOM_TXT_CDS <CURRENT_DESIGN_SHEET> OF <TOTAL_DESIGN_SHEETS>
J 0
(4800 -1625);
PAINT ORANGE (4800 -1625);
FORCEPROP 2 LAST CUSTOM_TXT_CDS <CON_LAST_MODIFIED>
J 0
(1300 -1550);
PAINT ORANGE (1300 -1550);
FORCEPROP 1 LAST SCH_TITLE VDDQ ABC VR (2 OF 3)
J 0
(-2650 -1600);
DISPLAY 1.212766 (-2650 -1600);
PAINT ORANGE (-2650 -1600);
FORCEPROP 2 LAST CDS_LIB mstr_symbols
J 0
(5300 -1650);
DISPLAY 1.936170 (5300 -1650);
PAINT ORANGE (5300 -1650);
DISPLAY INVISIBLE (5300 -1650);
FORCEPROP 2 LAST PAGE_BORDER TRUE
J 0
(-2590 3600);
DISPLAY 1.255319 (-2590 3600);
PAINT PINK (-2590 3600);
DISPLAY INVISIBLE (-2590 3600);
FORCEPROP 2 LAST ROOM CPU0_CORE_VR
J 0
(-2800 3450);
DISPLAY 1.936170 (-2800 3450);
PAINT ORANGE (-2800 3450);
DISPLAY INVISIBLE (-2800 3450);
FORCEPROP 1 LAST COMMENT_BODY TRUE
J 0
(5312 -1638);
DISPLAY 0.893617 (5312 -1638);
PAINT GREEN (5312 -1638);
DISPLAY INVISIBLE (5312 -1638);
FORCEPROP 2 LAST CDS_XR_PAGE_TITLE CR-216 : @BASEBOARD_FAB2_LIB.BASEBOARD_FAB2(SCH_1):PAGE216
J 0
(-2590 3600);
DISPLAY 0.638298 (-2590 3600);
PAINT PINK (-2590 3600);
DISPLAY INVISIBLE (-2590 3600);
FORCEADD DNS..2
(4580 2445);
PAINT RED (4580 2445);
FORCEPROP 1 LAST COMMENT_BODY TRUE
R 1
J 0
(4655 2220);
DISPLAY 0.872340 (4655 2220);
PAINT GREEN (4655 2220);
DISPLAY INVISIBLE (4655 2220);
FORCEPROP 2 LAST CDS_LIB mstr_misc
J 0
(4580 2445);
PAINT ORANGE (4580 2445);
DISPLAY INVISIBLE (4580 2445);
WIRE 16 -1 (4350 2050)(4350 2000);
WIRE 16 -1 (4250 2000)(4350 2000);
WIRE 16 -1 (4350 1950)(4350 2000);
WIRE 16 -1 (4250 1175)(4250 2000);
WIRE 16 -1 (4050 2000)(4250 2000);
WIRE 16 -1 (1150 1175)(4250 1175);
WIRE 16 -1 (1150 2450)(1150 1175);
WIRE 16 -1 (1275 2450)(1150 2450);
WIRE 16 -1 (4575 2300)(4575 2350);
WIRE 16 -1 (4675 -50)(4675 -125);
WIRE 16 -1 (1025 1700)(1025 1600);
WIRE 16 -1 (1125 -1050)(1125 -1100);
WIRE 16 -1 (2900 1325)(2900 1375);
WIRE 16 -1 (3000 2275)(3000 2225);
WIRE 16 -1 (2900 -975)(2900 -1000);
WIRE 16 -1 (2900 -175)(2900 -225);
WIRE 16 -1 (2450 1675)(2450 1750);
WIRE 16 -1 (2450 1750)(2450 1800);
WIRE 16 -1 (2275 1750)(2450 1750);
WIRE 16 -1 (2450 1800)(2450 1850);
WIRE 16 -1 (2450 1800)(2275 1800);
WIRE 16 -1 (2450 1850)(2450 1900);
WIRE 16 -1 (2450 1850)(2275 1850);
WIRE 16 -1 (2275 1900)(2450 1900);
WIRE 16 -1 (-2050 2100)(-2050 2250);
WIRE 16 -1 (-2050 2250)(-1775 2250);
WIRE 16 -1 (-2050 2425)(-2050 2250);
WIRE 16 -1 (-1775 2250)(-1525 2250);
WIRE 16 -1 (-1775 2425)(-1775 2250);
WIRE 16 -1 (-1525 2250)(-1275 2250);
WIRE 16 -1 (-1525 2425)(-1525 2250);
WIRE 16 -1 (-1275 2250)(-1000 2250);
WIRE 16 -1 (-1275 2425)(-1275 2250);
WIRE 16 -1 (-725 2250)(-1000 2250);
WIRE 16 -1 (-1000 2425)(-1000 2250);
WIRE 16 -1 (-725 2250)(-250 2250);
WIRE 16 -1 (-725 2425)(-725 2250);
WIRE 16 -1 (100 2250)(-250 2250);
WIRE 16 -1 (-250 2450)(-250 2250);
WIRE 16 -1 (100 2450)(100 2250);
WIRE 16 -1 (4400 -375)(4400 -325);
WIRE 16 -1 (4250 -375)(4400 -375);
WIRE 16 -1 (4400 -450)(4400 -375);
WIRE 16 -1 (4250 -1125)(4250 -375);
WIRE 16 -1 (4100 -375)(4250 -375);
WIRE 16 -1 (1200 -1125)(4250 -1125);
WIRE 16 -1 (1200 75)(1200 -1125);
WIRE 16 -1 (1275 75)(1200 75);
WIRE 16 -1 (4400 -750)(4400 -650);
WIRE 16 -1 (4350 1675)(4350 1750);
WIRE 16 -1 (2450 -775)(2450 -625);
WIRE 16 -1 (2450 -625)(2450 -575);
WIRE 16 -1 (2450 -625)(2275 -625);
WIRE 16 -1 (2450 -575)(2450 -525);
WIRE 16 -1 (2450 -575)(2275 -575);
WIRE 16 -1 (2450 -525)(2450 -475);
WIRE 16 -1 (2450 -525)(2275 -525);
WIRE 16 -1 (2275 -475)(2450 -475);
WIRE 16 -1 (-2050 425)(-2050 375);
WIRE 16 -1 (-2050 375)(-1800 375);
WIRE 16 -1 (-2050 275)(-2050 375);
WIRE 16 -1 (-1550 375)(-1800 375);
WIRE 16 -1 (-1800 275)(-1800 375);
WIRE 16 -1 (-1550 375)(-1325 375);
WIRE 16 -1 (-1550 275)(-1550 375);
WIRE 16 -1 (-1325 375)(-1075 375);
WIRE 16 -1 (-1325 275)(-1325 375);
WIRE 16 -1 (1075 375)(-1075 375);
WIRE 16 -1 (-1075 275)(-1075 375);
WIRE 16 -1 (1075 425)(1075 375);
WIRE 16 -1 (1275 375)(1075 375);
WIRE 16 -1 (1275 425)(1075 425);
WIRE 16 -1 (-2050 -125)(-2050 -100);
WIRE 16 -1 (-2050 -100)(-1800 -100);
WIRE 16 -1 (-2050 75)(-2050 -100);
WIRE 16 -1 (-1800 -100)(-1550 -100);
WIRE 16 -1 (-1800 75)(-1800 -100);
WIRE 16 -1 (-1550 -100)(-1325 -100);
WIRE 16 -1 (-1550 75)(-1550 -100);
WIRE 16 -1 (-1325 -100)(-1075 -100);
WIRE 16 -1 (-1325 75)(-1325 -100);
WIRE 16 -1 (-1075 -100)(-825 -100);
WIRE 16 -1 (-1075 75)(-1075 -100);
WIRE 16 -1 (-325 -100)(-825 -100);
WIRE 16 -1 (-825 75)(-825 -100);
WIRE 16 -1 (50 -100)(-325 -100);
WIRE 16 -1 (-325 100)(-325 -100);
WIRE 16 -1 (50 100)(50 -100);
WIRE 16 -1 (-1625 2850)(-1625 2750);
WIRE 16 -1 (-1525 2750)(-1625 2750);
WIRE 16 -1 (-1775 2750)(-1625 2750);
WIRE 16 -1 (-2050 2750)(-1775 2750);
WIRE 16 -1 (-1775 2625)(-1775 2750);
WIRE 16 -1 (-1525 2750)(-1275 2750);
WIRE 16 -1 (-1525 2625)(-1525 2750);
WIRE 16 -1 (-1275 2750)(-1000 2750);
WIRE 16 -1 (-1275 2625)(-1275 2750);
WIRE 16 -1 (-2050 2625)(-2050 2750);
WIRE 16 -1 (1075 2750)(-1000 2750);
WIRE 16 -1 (-1000 2625)(-1000 2750);
WIRE 16 -1 (1075 2800)(1075 2750);
WIRE 16 -1 (1275 2750)(1075 2750);
WIRE 16 -1 (1275 2800)(1075 2800);
WIRE 16 -1 (350 3100)(350 3200);
WIRE 16 -1 (350 3100)(350 2650);
WIRE 16 -1 (350 3100)(100 3100);
WIRE 16 -1 (100 3100)(-250 3100);
WIRE 16 -1 (100 2650)(100 3100);
WIRE 16 -1 (350 2650)(1200 2650);
WIRE 16 -1 (1200 2550)(1200 2650);
WIRE 16 -1 (1200 2650)(1275 2650);
WIRE 16 -1 (-475 3100)(-250 3100);
WIRE 16 -1 (-250 2600)(-250 3100);
WIRE 16 -1 (1275 2550)(1200 2550);
WIRE 16 -1 (500 850)(500 725);
WIRE 16 -1 (500 725)(500 275);
WIRE 16 -1 (50 725)(500 725);
WIRE 16 -1 (50 725)(-325 725);
WIRE 16 -1 (50 300)(50 725);
WIRE 16 -1 (500 275)(1175 275);
WIRE 16 -1 (1175 175)(1175 275);
WIRE 16 -1 (1175 275)(1275 275);
WIRE 16 -1 (-325 725)(-500 725);
WIRE 16 -1 (-325 250)(-325 725);
WIRE 16 -1 (1275 175)(1175 175);
WIRE 16 2175 (-1100 -625)(-100 -625);
WIRE 16 2175 (-100 -225)(-100 -625);
WIRE 16 2175 (-1100 -225)(-1100 -625);
WIRE 16 2175 (-1100 -225)(-100 -225);
WIRE 16 -1 (2275 2650)(4575 2650);
FORCEPROP 0 LAST VOLTAGE 3.6
J 0
(2350 2725);
DISPLAY 1.021277 (2350 2725);
PAINT SKYBLUE (2350 2725);
DISPLAY INVISIBLE (2350 2725);
FORCEPROP 2 LAST SIG_NAME VR_PVDDQ_ABC_PH1_OCSET
J 0
(2407 2666);
DISPLAY 0.617021 (2407 2666);
PAINT ORANGE (2407 2666);
FORCEPROP 2 LASTPROP $XRERR UNIQUE?
J 0
(2167 2666);
DISPLAY 0.638298 (2167 2666);
PAINT MONO (2167 2666);
DISPLAY INVISIBLE (2167 2666);
WIRE 16 -1 (4575 2550)(4575 2650);
WIRE 16 -1 (2275 275)(4675 275);
FORCEPROP 0 LAST VOLTAGE 3.6
J 0
(2350 350);
DISPLAY 1.021277 (2350 350);
PAINT SKYBLUE (2350 350);
DISPLAY INVISIBLE (2350 350);
FORCEPROP 2 LAST SIG_NAME VR_PVDDQ_ABC_PH2_OCSET
J 0
(2407 291);
DISPLAY 0.617021 (2407 291);
PAINT ORANGE (2407 291);
FORCEPROP 2 LASTPROP $XRERR UNIQUE?
J 0
(2167 291);
DISPLAY 0.638298 (2167 291);
PAINT MONO (2167 291);
DISPLAY INVISIBLE (2167 291);
WIRE 16 -1 (4675 275)(4675 150);
WIRE 3 2175 (2825 2575)(2825 2100);
WIRE 3 2175 (2825 2100)(3250 2100);
WIRE 3 2175 (2825 2575)(3250 2575);
WIRE 3 2175 (3250 2575)(3250 2100);
WIRE 16 -1 (2275 2850)(3575 2850);
FORCEPROP 2 LAST SIG_NAME ISENSE_PVDDQ_ABC_PH1_IMON
J 0
(2587 2860);
DISPLAY 0.617021 (2587 2860);
PAINT ORANGE (2587 2860);
WIRE 3 2175 (2800 1250)(3650 1250);
WIRE 3 2175 (3650 2050)(3650 1250);
WIRE 3 2175 (2800 2050)(2800 1250);
WIRE 3 2175 (2800 2050)(3650 2050);
WIRE 16 -1 (2275 2350)(2350 2350);
WIRE 16 -1 (2350 2350)(2350 2500);
WIRE 16 -1 (2350 2500)(3000 2500);
FORCEPROP 2 LAST SIG_NAME A_TSENSE_PVDDQ_ABC
J 0
(2362 2510);
DISPLAY 0.617021 (2362 2510);
PAINT ORANGE (2362 2510);
WIRE 16 -1 (3000 2500)(3000 2475);
WIRE 16 -1 (3000 2500)(3575 2500);
WIRE 3 682 (2350 2600)(2450 2600);
WIRE 16 -1 (2900 1625)(2900 1700);
WIRE 16 -1 (2900 1750)(2900 1700);
WIRE 16 -1 (3600 1700)(2900 1700);
FORCEPROP 2 LAST SIG_NAME VR_PVDDQ_ABC_PH1_SW_RC
J 0
(3060 1710);
DISPLAY 0.617021 (3060 1710);
PAINT ORANGE (3060 1710);
FORCEPROP 2 LASTPROP $XRERR UNIQUE?
J 0
(3630 1700);
DISPLAY 0.638298 (3630 1700);
PAINT MONO (3630 1700);
DISPLAY INVISIBLE (3630 1700);
WIRE 16 -1 (2275 2000)(2900 2000);
FORCEPROP 2 LAST SIG_NAME VR_PVDDQ_ABC_PH1_SW
J 0
(2335 2010);
DISPLAY 0.617021 (2335 2010);
PAINT ORANGE (2335 2010);
FORCEPROP 2 LASTPROP $XRERR UNIQUE?
J 0
(2095 2010);
DISPLAY 0.638298 (2095 2010);
PAINT MONO (2095 2010);
DISPLAY INVISIBLE (2095 2010);
WIRE 16 -1 (2900 1950)(2900 2000);
WIRE 16 -1 (3750 2000)(2900 2000);
WIRE 16 -1 (2275 475)(3425 475);
FORCEPROP 2 LAST SIG_NAME ISENSE_PVDDQ_ABC_PH2_IMON
J 0
(2387 485);
DISPLAY 0.617021 (2387 485);
PAINT ORANGE (2387 485);
WIRE 3 2175 (2650 -300)(3175 -300);
WIRE 3 2175 (3175 50)(3175 -300);
WIRE 3 2175 (2650 50)(2650 -300);
WIRE 3 2175 (2650 50)(3175 50);
WIRE 16 -1 (2275 100)(2275 -25);
WIRE 16 -1 (2275 100)(2900 100);
FORCEPROP 2 LAST SIG_NAME A_TSENSE_PVDDQ_ABC
J 0
(2287 110);
DISPLAY 0.617021 (2287 110);
PAINT ORANGE (2287 110);
WIRE 16 -1 (2900 25)(2900 100);
WIRE 16 -1 (2900 100)(3575 100);
WIRE 3 682 (2350 225)(2450 225);
WIRE 16 -1 (1025 1900)(1025 2100);
WIRE 16 -1 (1275 2100)(1025 2100);
WIRE 16 -1 (1025 2100)(1025 3175);
WIRE 16 -1 (1025 3175)(3550 3175);
FORCEPROP 2 LAST SIG_NAME VR_PVDDQ_ABC_AIREF1
J 0
(2900 3185);
DISPLAY 0.617021 (2900 3185);
PAINT ORANGE (2900 3185);
WIRE 16 -1 (1125 -850)(1125 -275);
WIRE 16 -1 (1275 -275)(1125 -275);
WIRE 16 -1 (1125 -275)(1125 800);
WIRE 16 -1 (3425 800)(1125 800);
FORCEPROP 2 LAST SIG_NAME VR_PVDDQ_ABC_AIREF2
J 0
(2761 798);
DISPLAY 0.617021 (2761 798);
PAINT ORANGE (2761 798);
WIRE 16 -1 (300 2300)(1275 2300);
FORCEPROP 0 LAST SIG_NAME TP_PVDDQ_ABC_PH1_GL_0
J 0
(327 2315);
DISPLAY 0.617021 (327 2315);
PAINT ORANGE (327 2315);
FORCEPROP 2 LASTPROP $XRERR UNIQUE?
J 0
(60 2300);
DISPLAY 0.638298 (60 2300);
PAINT MONO (60 2300);
DISPLAY INVISIBLE (60 2300);
WIRE 16 -1 (300 2350)(1275 2350);
FORCEPROP 0 LAST SIG_NAME TP_PVDDQ_ABC_PH1_GL_1
J 0
(327 2365);
DISPLAY 0.617021 (327 2365);
PAINT ORANGE (327 2365);
FORCEPROP 2 LASTPROP $XRERR UNIQUE?
J 0
(60 2350);
DISPLAY 0.638298 (60 2350);
PAINT MONO (60 2350);
DISPLAY INVISIBLE (60 2350);
WIRE 16 -1 (900 2000)(1275 2000);
WIRE 16 -1 (900 2075)(900 2000);
WIRE 16 -1 (225 2075)(900 2075);
FORCEPROP 2 LAST SIG_NAME VR_PVDDQ_ABC_PH1_BOOT_R
J 0
(360 2085);
DISPLAY 0.617021 (360 2085);
PAINT ORANGE (360 2085);
FORCEPROP 2 LASTPROP $XRERR UNIQUE?
J 0
(120 2085);
DISPLAY 0.638298 (120 2085);
PAINT MONO (120 2085);
DISPLAY INVISIBLE (120 2085);
WIRE 16 2175 (-450 2700)(-450 2300);
WIRE 16 2175 (-450 2300)(250 2300);
WIRE 16 2175 (-450 2700)(250 2700);
WIRE 16 2175 (250 2700)(250 2300);
WIRE 3 2175 (-75 2175)(-75 1925);
WIRE 3 2175 (-75 1925)(350 1925);
WIRE 3 2175 (-75 2175)(350 2175);
WIRE 3 2175 (350 2175)(350 1925);
WIRE 16 -1 (-675 1800)(-675 1825);
WIRE 16 -1 (-675 1800)(900 1800);
FORCEPROP 2 LAST SIG_NAME VR_PVDDQ_ABC_PH1_PHASE
J 0
(-665 1810);
DISPLAY 0.617021 (-665 1810);
PAINT ORANGE (-665 1810);
FORCEPROP 2 LASTPROP $XRERR UNIQUE?
J 0
(-905 1810);
DISPLAY 0.638298 (-905 1810);
PAINT MONO (-905 1810);
DISPLAY INVISIBLE (-905 1810);
WIRE 16 -1 (900 1800)(900 1950);
WIRE 16 -1 (900 1950)(1275 1950);
WIRE 3 682 (-2350 -1300)(-2350 1000);
WIRE 3 682 (-2350 -1300)(5150 -1300);
WIRE 3 682 (-2350 1000)(5150 1000);
WIRE 3 682 (5150 1000)(5150 -1300);
WIRE 16 2175 (-525 350)(-525 -50);
WIRE 16 2175 (-525 -50)(200 -50);
WIRE 16 2175 (-525 350)(200 350);
WIRE 16 2175 (200 350)(200 -50);
WIRE 3 2175 (2800 -350)(2800 -1075);
WIRE 3 2175 (2800 -1075)(3550 -1075);
WIRE 3 2175 (2800 -350)(3550 -350);
WIRE 3 2175 (3550 -350)(3550 -1075);
WIRE 16 -1 (2900 -725)(2900 -675);
WIRE 16 -1 (2900 -675)(2900 -625);
WIRE 16 -1 (2900 -675)(3500 -675);
FORCEPROP 2 LAST SIG_NAME VR_PVDDQ_ABC_PH2_SW_RC
J 0
(2985 -665);
DISPLAY 0.617021 (2985 -665);
PAINT ORANGE (2985 -665);
FORCEPROP 2 LASTPROP $XRERR UNIQUE?
J 0
(3530 -675);
DISPLAY 0.638298 (3530 -675);
PAINT MONO (3530 -675);
DISPLAY INVISIBLE (3530 -675);
WIRE 16 -1 (2275 -375)(2900 -375);
FORCEPROP 2 LAST SIG_NAME VR_PVDDQ_ABC_PH2_SW
J 0
(2360 -365);
DISPLAY 0.617021 (2360 -365);
PAINT ORANGE (2360 -365);
FORCEPROP 2 LASTPROP $XRERR UNIQUE?
J 0
(2120 -365);
DISPLAY 0.638298 (2120 -365);
PAINT MONO (2120 -365);
DISPLAY INVISIBLE (2120 -365);
WIRE 16 -1 (2900 -425)(2900 -375);
WIRE 16 -1 (3800 -375)(2900 -375);
WIRE 16 -1 (-800 -525)(-800 -575);
WIRE 16 -1 (-800 -575)(1000 -575);
FORCEPROP 2 LAST SIG_NAME VR_PVDDQ_ABC_PH2_PHASE
J 0
(-790 -565);
DISPLAY 0.617021 (-790 -565);
PAINT ORANGE (-790 -565);
FORCEPROP 2 LASTPROP $XRERR UNIQUE?
J 0
(-1030 -565);
DISPLAY 0.638298 (-1030 -565);
PAINT MONO (-1030 -565);
DISPLAY INVISIBLE (-1030 -565);
WIRE 16 -1 (1000 -425)(1000 -575);
WIRE 16 -1 (1275 -425)(1000 -425);
WIRE 16 -1 (200 -275)(1000 -275);
FORCEPROP 2 LAST SIG_NAME VR_PVDDQ_ABC_PH2_BOOT_R
J 0
(310 -265);
DISPLAY 0.617021 (310 -265);
PAINT ORANGE (310 -265);
FORCEPROP 2 LASTPROP $XRERR UNIQUE?
J 0
(70 -265);
DISPLAY 0.638298 (70 -265);
PAINT MONO (70 -265);
DISPLAY INVISIBLE (70 -265);
WIRE 16 -1 (1000 -375)(1000 -275);
WIRE 16 -1 (1275 -375)(1000 -375);
WIRE 16 -1 (300 -25)(1275 -25);
FORCEPROP 0 LAST SIG_NAME TP_PVDDQ_ABC_PH2_GL_1
J 0
(327 -10);
DISPLAY 0.617021 (327 -10);
PAINT ORANGE (327 -10);
FORCEPROP 2 LASTPROP $XRERR UNIQUE?
J 0
(60 -25);
DISPLAY 0.638298 (60 -25);
PAINT MONO (60 -25);
DISPLAY INVISIBLE (60 -25);
WIRE 16 -1 (300 -75)(1275 -75);
FORCEPROP 0 LAST SIG_NAME TP_PVDDQ_ABC_PH2_GL_0
J 0
(327 -60);
DISPLAY 0.617021 (327 -60);
PAINT ORANGE (327 -60);
FORCEPROP 2 LASTPROP $XRERR UNIQUE?
J 0
(60 -75);
DISPLAY 0.638298 (60 -75);
PAINT MONO (60 -75);
DISPLAY INVISIBLE (60 -75);
WIRE 16 -1 (500 -175)(1275 -175);
FORCEPROP 2 LAST SIG_NAME VR_PVDDQ_ABC_PWM2
J 0
(487 -165);
DISPLAY 0.617021 (487 -165);
PAINT ORANGE (487 -165);
WIRE 3 2175 (-50 -200)(-50 -450);
WIRE 3 2175 (-50 -450)(250 -450);
WIRE 3 2175 (-50 -200)(250 -200);
WIRE 3 2175 (250 -200)(250 -450);
WIRE 16 -1 (-675 2075)(-675 2025);
WIRE 16 -1 (25 2075)(-675 2075);
FORCEPROP 2 LAST SIG_NAME VR_PVDDQ_ABC_PH1_BOOT
J 0
(-665 2085);
DISPLAY 0.617021 (-665 2085);
PAINT ORANGE (-665 2085);
FORCEPROP 2 LASTPROP $XRERR UNIQUE?
J 0
(-905 2085);
DISPLAY 0.638298 (-905 2085);
PAINT MONO (-905 2085);
DISPLAY INVISIBLE (-905 2085);
WIRE 16 -1 (-1475 2200)(1275 2200);
WIRE 16 -1 (-725 3100)(-675 3100);
WIRE 16 -1 (-725 2625)(-725 2850);
WIRE 16 -1 (-725 2850)(-725 3100);
FORCEPROP 2 LAST SIG_NAME VR_PVDDQ_ABC_PH1_VCIN
J 0
(-690 2860);
DISPLAY 0.617021 (-690 2860);
PAINT ORANGE (-690 2860);
FORCEPROP 2 LASTPROP $XRERR UNIQUE?
J 0
(-930 2860);
DISPLAY 0.638298 (-930 2860);
PAINT MONO (-930 2860);
DISPLAY INVISIBLE (-930 2860);
WIRE 16 -1 (-725 2850)(1275 2850);
WIRE 16 -1 (-800 -275)(-800 -325);
WIRE 16 -1 (0 -275)(-800 -275);
FORCEPROP 2 LAST SIG_NAME VR_PVDDQ_ABC_PH2_BOOT
J 0
(-765 -265);
DISPLAY 0.617021 (-765 -265);
PAINT ORANGE (-765 -265);
FORCEPROP 2 LASTPROP $XRERR UNIQUE?
J 0
(-1005 -265);
DISPLAY 0.638298 (-1005 -265);
PAINT MONO (-1005 -265);
DISPLAY INVISIBLE (-1005 -265);
WIRE 16 -1 (-825 725)(-700 725);
WIRE 16 -1 (-825 275)(-825 475);
WIRE 16 -1 (-825 725)(-825 475);
WIRE 16 -1 (-825 475)(1275 475);
FORCEPROP 2 LAST SIG_NAME VR_PVDDQ_ABC_PH2_VCIN
J 0
(-765 485);
DISPLAY 0.617021 (-765 485);
PAINT ORANGE (-765 485);
FORCEPROP 2 LASTPROP $XRERR UNIQUE?
J 0
(-1005 485);
DISPLAY 0.638298 (-1005 485);
PAINT MONO (-1005 485);
DISPLAY INVISIBLE (-1005 485);
WIRE 3 2175 (-750 2950)(-350 2950);
WIRE 3 2175 (-350 3200)(-350 2950);
WIRE 3 2175 (-750 3200)(-750 2950);
WIRE 3 2175 (-750 3200)(-350 3200);
WIRE 3 682 (-200 2350)(-300 2350);
WIRE 3 682 (-300 2350)(-300 2650);
WIRE 3 682 (-200 2650)(-200 2350);
WIRE 3 682 (-200 2650)(-300 2650);
WIRE 16 2175 (-1025 1650)(-125 1650);
WIRE 16 2175 (-125 2150)(-125 1650);
WIRE 16 2175 (-1025 2150)(-1025 1650);
WIRE 16 2175 (-1025 2150)(-125 2150);
WIRE 3 2175 (-775 825)(-775 575);
WIRE 3 2175 (-775 575)(-425 575);
WIRE 3 2175 (-775 825)(-425 825);
WIRE 3 2175 (-425 825)(-425 575);
WIRE 3 682 (-275 25)(-375 25);
WIRE 3 682 (-375 25)(-375 300);
WIRE 3 682 (-275 300)(-275 25);
WIRE 3 682 (-275 300)(-375 300);
WIRE 3 682 (-900 -50)(-2100 -50);
WIRE 3 682 (-900 350)(-900 -50);
WIRE 3 682 (-2100 -50)(-2100 350);
WIRE 3 682 (-2100 350)(-900 350);
DOT 1 (4350 2000);
DOT 1 (4250 2000);
DOT 1 (3000 2500);
DOT 1 (2900 2000);
DOT 1 (2900 1700);
DOT 1 (2450 1850);
DOT 1 (2450 1800);
DOT 1 (2450 1750);
DOT 1 (2900 100);
DOT 1 (1200 2650);
DOT 1 (1075 2750);
DOT 1 (1025 2100);
DOT 1 (350 3100);
DOT 1 (100 3100);
DOT 1 (1175 275);
DOT 1 (1075 375);
DOT 1 (500 725);
DOT 1 (50 725);
DOT 1 (4400 -375);
DOT 1 (4250 -375);
DOT 1 (2900 -375);
DOT 1 (2900 -675);
DOT 1 (2450 -525);
DOT 1 (2450 -575);
DOT 1 (2450 -625);
DOT 1 (1125 -275);
DOT 1 (-250 3100);
DOT 1 (-250 2250);
DOT 1 (-725 2850);
DOT 1 (-1000 2750);
DOT 1 (-725 2250);
DOT 1 (-1000 2250);
DOT 1 (-1275 2750);
DOT 1 (-1275 2250);
DOT 1 (-1525 2750);
DOT 1 (-1525 2250);
DOT 1 (-1625 2750);
DOT 1 (-1775 2750);
DOT 1 (-1775 2250);
DOT 1 (-325 725);
DOT 1 (-825 475);
DOT 1 (-1075 375);
DOT 1 (-1325 375);
DOT 1 (-1550 375);
DOT 1 (-1800 375);
DOT 1 (-2050 2250);
DOT 1 (-2050 375);
DOT 1 (-325 -100);
DOT 1 (-825 -100);
DOT 1 (-1075 -100);
DOT 1 (-1325 -100);
DOT 1 (-1550 -100);
DOT 1 (-1800 -100);
DOT 1 (-2050 -100);
FORCENOTE
TP FAB1 CO-LAY WITH TI PARTS 11/16
(3300 2425) 0;
DISPLAY LEFT (3300 2425);
DISPLAY 0.638298 (3300 2425);
PAINT RED (3300 2425);
FORCENOTE
TP FAB3 CHANGE L7G1 0823
(3600 2250) 0;
DISPLAY LEFT (3600 2250);
DISPLAY 0.638298 (3600 2250);
PAINT RED (3600 2250);
FORCENOTE
TP FAB1 CHANGE L7G1 PN 0122
(3600 2300) 0;
DISPLAY LEFT (3600 2300);
DISPLAY 0.638298 (3600 2300);
PAINT RED (3600 2300);
FORCENOTE
TP FAB3-DVT NOPOP L7G1 IND FOR SS BOM 20161215
(3600 2200) 0;
DISPLAY LEFT (3600 2200);
DISPLAY 0.638298 (3600 2200);
PAINT RED (3600 2200);
FORCENOTE
TP FAB1 CO-LAY WITH TI PARTS 11/16
(2850 1100) 0;
DISPLAY LEFT (2850 1100);
DISPLAY 0.851064 (2850 1100);
PAINT RED (2850 1100);
FORCENOTE
TP FAB1 CHANGE RES TO 1 OHM 0603 0107
(2825 1025) 0;
DISPLAY LEFT (2825 1025);
DISPLAY 1.021277 (2825 1025);
PAINT RED (2825 1025);
FORCENOTE
TP FAB1 DEL NET 0309
(2475 2600) 0;
DISPLAY LEFT (2475 2600);
DISPLAY 1.021277 (2475 2600);
PAINT RED (2475 2600);
FORCENOTE
TP FAB1 ADD NET NAME 12/04
(2800 1200) 0;
DISPLAY LEFT (2800 1200);
DISPLAY 0.680851 (2800 1200);
PAINT RED (2800 1200);
FORCENOTE
TP FAB1 DEL NET 0309
(2500 200) 0;
DISPLAY LEFT (2500 200);
DISPLAY 1.021277 (2500 200);
PAINT RED (2500 200);
FORCENOTE
TDA21470
(1600 2925) 0;
DISPLAY LEFT (1600 2925);
DISPLAY 1.021277 (1600 2925);
PAINT SKYBLUE (1600 2925);
FORCENOTE
TDA21470
(1600 550) 0;
DISPLAY LEFT (1600 550);
DISPLAY 1.021277 (1600 550);
PAINT SKYBLUE (1600 550);
FORCENOTE
TP FAB1 CO-LAY WITH TI PARTS 11/16
(3200 0) 0;
DISPLAY LEFT (3200 0);
DISPLAY 0.702128 (3200 0);
PAINT RED (3200 0);
FORCENOTE
TP FAB1 CHANGE L7G2 PN 0122
(3625 -100) 0;
DISPLAY LEFT (3625 -100);
DISPLAY 0.638298 (3625 -100);
PAINT RED (3625 -100);
FORCENOTE
TP FAB3 CHANGE L7G2 0823
(3625 -150) 0;
DISPLAY LEFT (3625 -150);
DISPLAY 0.638298 (3625 -150);
PAINT RED (3625 -150);
FORCENOTE
TP FAB3-DVT NOPOP L7G2 IND FOR SS BOM 20161215
(3625 -200) 0;
DISPLAY LEFT (3625 -200);
DISPLAY 0.638298 (3625 -200);
PAINT RED (3625 -200);
FORCENOTE
TP FAB1 ADD NET NAME 12/04
(3100 -725) 0;
DISPLAY LEFT (3100 -725);
DISPLAY 0.680851 (3100 -725);
PAINT RED (3100 -725);
FORCENOTE
TP FAB1CO-LAY WITH TI PARTS 11/16
(2800 -1125) 0;
DISPLAY LEFT (2800 -1125);
DISPLAY 0.680851 (2800 -1125);
PAINT RED (2800 -1125);
FORCENOTE
TP FAB1 CHANGE RES TO 1 OHM 0603 0107
(2800 -1175) 0;
DISPLAY LEFT (2800 -1175);
DISPLAY 0.638298 (2800 -1175);
PAINT RED (2800 -1175);
FORCENOTE
TP FAB1 CHANGE PN 0310
(-425 375) 0;
DISPLAY LEFT (-425 375);
DISPLAY 1.021277 (-425 375);
PAINT RED (-425 375);
FORCENOTE
PLACE ON TOP
(-555 -125) 0;
DISPLAY LEFT (-555 -125);
DISPLAY 1.553191 (-555 -125);
PAINT PURPLE (-555 -125);
FORCENOTE
TP FAB1 CHANGE PN 0310
(-300 2725) 0;
DISPLAY LEFT (-300 2725);
DISPLAY 1.021277 (-300 2725);
PAINT RED (-300 2725);
FORCENOTE
TP FAB1 CO-LAY WITH TI PARTS 11/16
(-200 -775) 0;
DISPLAY LEFT (-200 -775);
DISPLAY 0.851064 (-200 -775);
PAINT RED (-200 -775);
FORCENOTE
ROOM = VDDQ_ABC_PWR_VR
(-2630 -1500) 0;
DISPLAY LEFT (-2630 -1500);
DISPLAY 2.893617 (-2630 -1500);
PAINT PURPLE (-2630 -1500);
FORCENOTE
TP FAB1 CO-LAY WITH TI PARTS 11/16
(-125 1550) 0;
DISPLAY LEFT (-125 1550);
DISPLAY 0.851064 (-125 1550);
PAINT RED (-125 1550);
FORCENOTE
TP FAB1 CHANGE TO 0 OHM 0107
(-850 3200) 0;
DISPLAY LEFT (-850 3200);
DISPLAY 0.638298 (-850 3200);
PAINT RED (-850 3200);
FORCENOTE
SPOF
(-530 1625) 0;
DISPLAY LEFT (-530 1625);
DISPLAY 1.936170 (-530 1625);
PAINT PURPLE (-530 1625);
FORCENOTE
TP FAB1 CHANGE TO 0 OHM 0107
(-925 825) 0;
DISPLAY LEFT (-925 825);
DISPLAY 0.638298 (-925 825);
PAINT RED (-925 825);
FORCENOTE
TP FAB3-DVT NOPOP FROM SS BOM 20161215
(-2350 1025) 0;
DISPLAY LEFT (-2350 1025);
DISPLAY 0.638298 (-2350 1025);
PAINT RED (-2350 1025);
FORCENOTE
SPOF
(-630 -800) 0;
DISPLAY LEFT (-630 -800);
DISPLAY 1.808511 (-630 -800);
PAINT PURPLE (-630 -800);
FORCENOTE
TP FAB4 POP CAP ON SS BOM 20170207
(-2025 -150) 0;
DISPLAY LEFT (-2025 -150);
DISPLAY 0.638298 (-2025 -150);
PAINT RED (-2025 -150);
FORCENOTE
PLACE ON TOP
(-455 2225) 0;
DISPLAY LEFT (-455 2225);
DISPLAY 1.553191 (-455 2225);
PAINT PURPLE (-455 2225);
QUIT
